(kicad_sch (version 20230121) (generator eeschema)

  (paper "A3")

  (title_block
    (title "Kria K26 Devboard")
    (date "2024-03-26")
    (rev "1.2.5")
    (comment 1 "www.antmicro.com")
    (comment 2 "Antmicro Ltd.")
  )

  (junction (at 60.96 123.19) (diameter 0) (color 0 0 0 0)
  )
  (junction (at 308.61 55.88) (diameter 0) (color 0 0 0 0)
  )
  (junction (at 319.405 137.16) (diameter 0) (color 0 0 0 0)
  )
  (junction (at 339.725 152.4) (diameter 0) (color 0 0 0 0)
  )
  (junction (at 102.235 154.94) (diameter 0) (color 0 0 0 0)
  )
  (junction (at 45.72 100.965) (diameter 0) (color 0 0 0 0)
  )
  (junction (at 168.275 53.975) (diameter 0) (color 0 0 0 0)
  )
  (junction (at 51.308 203.2) (diameter 0) (color 0 0 0 0)
  )
  (junction (at 308.61 50.8) (diameter 0) (color 0 0 0 0)
  )
  (junction (at 339.725 137.16) (diameter 0) (color 0 0 0 0)
  )
  (junction (at 184.785 127) (diameter 0) (color 0 0 0 0)
  )
  (junction (at 132.588 261.62) (diameter 0) (color 0 0 0 0)
  )
  (junction (at 159.385 53.975) (diameter 0) (color 0 0 0 0)
  )
  (junction (at 180.848 266.7) (diameter 0) (color 0 0 0 0)
  )
  (junction (at 218.44 264.16) (diameter 0) (color 0 0 0 0)
  )
  (junction (at 51.308 153.67) (diameter 0) (color 0 0 0 0)
  )
  (junction (at 97.79 34.925) (diameter 0) (color 0 0 0 0)
  )
  (junction (at 204.47 60.96) (diameter 0) (color 0 0 0 0)
  )
  (junction (at 22.86 100.965) (diameter 0) (color 0 0 0 0)
  )
  (junction (at 22.86 123.19) (diameter 0) (color 0 0 0 0)
  )
  (junction (at 123.19 57.15) (diameter 0) (color 0 0 0 0)
  )
  (junction (at 218.44 261.62) (diameter 0) (color 0 0 0 0)
  )
  (junction (at 262.89 264.16) (diameter 0) (color 0 0 0 0)
  )
  (junction (at 352.425 137.16) (diameter 0) (color 0 0 0 0)
  )
  (junction (at 116.84 154.94) (diameter 0) (color 0 0 0 0)
  )
  (junction (at 165.735 53.975) (diameter 0) (color 0 0 0 0)
  )
  (junction (at 38.1 123.19) (diameter 0) (color 0 0 0 0)
  )
  (junction (at 142.748 271.78) (diameter 0) (color 0 0 0 0)
  )
  (junction (at 54.61 40.64) (diameter 0) (color 0 0 0 0)
  )
  (junction (at 260.35 261.62) (diameter 0) (color 0 0 0 0)
  )
  (junction (at 185.42 214.63) (diameter 0) (color 0 0 0 0)
  )
  (junction (at 361.95 137.16) (diameter 0) (color 0 0 0 0)
  )
  (junction (at 166.878 269.24) (diameter 0) (color 0 0 0 0)
  )
  (junction (at 54.61 33.02) (diameter 0) (color 0 0 0 0)
  )
  (junction (at 38.1 100.965) (diameter 0) (color 0 0 0 0)
  )
  (junction (at 306.705 94.615) (diameter 0) (color 0 0 0 0)
  )
  (junction (at 241.3 41.91) (diameter 0) (color 0 0 0 0)
  )
  (junction (at 218.44 266.7) (diameter 0) (color 0 0 0 0)
  )
  (junction (at 302.26 104.775) (diameter 0) (color 0 0 0 0)
  )
  (junction (at 217.17 49.53) (diameter 0) (color 0 0 0 0)
  )
  (junction (at 342.265 154.94) (diameter 0) (color 0 0 0 0)
  )
  (junction (at 233.68 41.91) (diameter 0) (color 0 0 0 0)
  )
  (junction (at 37.465 48.26) (diameter 0) (color 0 0 0 0)
  )
  (junction (at 231.14 128.27) (diameter 0) (color 0 0 0 0)
  )
  (junction (at 257.81 259.08) (diameter 0) (color 0 0 0 0)
  )
  (junction (at 123.19 34.925) (diameter 0) (color 0 0 0 0)
  )
  (junction (at 177.038 251.46) (diameter 0) (color 0 0 0 0)
  )
  (junction (at 177.038 264.16) (diameter 0) (color 0 0 0 0)
  )
  (junction (at 51.308 177.8) (diameter 0) (color 0 0 0 0)
  )
  (junction (at 297.18 198.12) (diameter 0) (color 0 0 0 0)
  )
  (junction (at 297.18 157.48) (diameter 0) (color 0 0 0 0)
  )
  (junction (at 218.44 269.24) (diameter 0) (color 0 0 0 0)
  )
  (junction (at 220.98 49.53) (diameter 0) (color 0 0 0 0)
  )
  (junction (at 52.07 40.64) (diameter 0) (color 0 0 0 0)
  )
  (junction (at 265.43 266.7) (diameter 0) (color 0 0 0 0)
  )
  (junction (at 218.44 259.08) (diameter 0) (color 0 0 0 0)
  )
  (junction (at 93.98 57.15) (diameter 0) (color 0 0 0 0)
  )
  (junction (at 100.965 57.15) (diameter 0) (color 0 0 0 0)
  )
  (junction (at 185.42 212.09) (diameter 0) (color 0 0 0 0)
  )
  (junction (at 185.42 217.17) (diameter 0) (color 0 0 0 0)
  )
  (junction (at 56.515 226.695) (diameter 0) (color 0 0 0 0)
  )
  (junction (at 334.01 107.315) (diameter 0) (color 0 0 0 0)
  )
  (junction (at 45.72 123.19) (diameter 0) (color 0 0 0 0)
  )
  (junction (at 238.76 243.84) (diameter 0) (color 0 0 0 0)
  )
  (junction (at 342.265 137.16) (diameter 0) (color 0 0 0 0)
  )
  (junction (at 306.705 97.155) (diameter 0) (color 0 0 0 0)
  )
  (junction (at 187.198 261.62) (diameter 0) (color 0 0 0 0)
  )
  (junction (at 187.198 251.46) (diameter 0) (color 0 0 0 0)
  )
  (junction (at 53.34 123.19) (diameter 0) (color 0 0 0 0)
  )
  (junction (at 38.735 50.8) (diameter 0) (color 0 0 0 0)
  )
  (junction (at 321.31 220.98) (diameter 0) (color 0 0 0 0)
  )
  (junction (at 53.34 100.965) (diameter 0) (color 0 0 0 0)
  )
  (junction (at 30.48 100.965) (diameter 0) (color 0 0 0 0)
  )
  (junction (at 102.235 34.925) (diameter 0) (color 0 0 0 0)
  )
  (junction (at 30.48 123.19) (diameter 0) (color 0 0 0 0)
  )

  (no_connect (at 227.33 190.5))
  (no_connect (at 144.78 266.7))
  (no_connect (at 227.33 152.4))
  (no_connect (at 227.33 166.37))
  (no_connect (at 227.33 209.55))
  (no_connect (at 36.195 63.5))
  (no_connect (at 227.33 204.47))
  (no_connect (at 227.33 215.9))
  (no_connect (at 227.33 195.58))
  (no_connect (at 227.33 142.24))
  (no_connect (at 227.33 193.04))
  (no_connect (at 229.87 269.24))
  (no_connect (at 227.33 154.94))
  (no_connect (at 227.33 147.32))
  (no_connect (at 227.33 173.99))
  (no_connect (at 227.33 144.78))
  (no_connect (at 309.88 107.315))
  (no_connect (at 309.88 102.235))
  (no_connect (at 227.33 187.96))
  (no_connect (at 36.195 60.96))
  (no_connect (at 328.93 68.58))
  (no_connect (at 227.33 149.86))
  (no_connect (at 186.69 137.16))
  (no_connect (at 186.69 134.62))
  (no_connect (at 227.33 163.83))
  (no_connect (at 118.745 59.69))
  (no_connect (at 118.745 37.465))
  (no_connect (at 227.33 171.45))
  (no_connect (at 227.33 201.93))
  (no_connect (at 59.69 50.8))
  (no_connect (at 227.33 198.12))
  (no_connect (at 227.33 185.42))
  (no_connect (at 227.33 176.53))
  (no_connect (at 227.33 168.91))
  (no_connect (at 227.33 180.34))

  (bus_entry (at 168.91 153.67) (size 2.54 2.54)
    (stroke (width 0) (type default))
  )
  (bus_entry (at 168.91 151.13) (size 2.54 2.54)
    (stroke (width 0) (type default))
  )

  (wire (pts (xy 316.23 154.94) (xy 342.265 154.94))
    (stroke (width 0) (type default))
  )
  (wire (pts (xy 260.35 261.62) (xy 269.875 261.62))
    (stroke (width 0) (type default))
  )
  (wire (pts (xy 257.81 252.095) (xy 257.81 259.08))
    (stroke (width 0) (type default))
  )
  (wire (pts (xy 37.465 230.759) (xy 21.463 230.759))
    (stroke (width 0) (type default))
  )
  (wire (pts (xy 336.55 86.995) (xy 328.93 86.995))
    (stroke (width 0) (type default))
  )
  (wire (pts (xy 299.085 86.995) (xy 309.88 86.995))
    (stroke (width 0) (type default))
  )
  (wire (pts (xy 38.1 71.12) (xy 38.1 76.835))
    (stroke (width 0) (type default))
  )
  (wire (pts (xy 172.72 151.13) (xy 186.69 151.13))
    (stroke (width 0) (type default))
  )
  (wire (pts (xy 281.94 187.96) (xy 297.815 187.96))
    (stroke (width 0) (type default))
  )
  (wire (pts (xy 22.86 124.46) (xy 22.86 123.19))
    (stroke (width 0) (type default))
  )
  (wire (pts (xy 116.84 154.94) (xy 123.825 154.94))
    (stroke (width 0) (type default))
  )
  (wire (pts (xy 268.605 149.225) (xy 278.13 149.225))
    (stroke (width 0) (type default))
  )
  (wire (pts (xy 140.462 121.92) (xy 127 121.92))
    (stroke (width 0) (type default))
  )
  (wire (pts (xy 233.68 44.45) (xy 233.68 41.91))
    (stroke (width 0) (type default))
  )
  (wire (pts (xy 56.515 230.759) (xy 56.515 226.695))
    (stroke (width 0) (type default))
  )
  (wire (pts (xy 177.038 264.16) (xy 196.85 264.16))
    (stroke (width 0) (type default))
  )
  (wire (pts (xy 233.68 41.91) (xy 233.68 38.735))
    (stroke (width 0) (type default))
  )
  (wire (pts (xy 186.69 171.45) (xy 172.72 171.45))
    (stroke (width 0) (type default))
  )
  (wire (pts (xy 361.95 137.16) (xy 374.65 137.16))
    (stroke (width 0) (type default))
  )
  (wire (pts (xy 86.995 34.925) (xy 97.79 34.925))
    (stroke (width 0) (type default))
  )
  (wire (pts (xy 321.31 220.98) (xy 321.31 219.71))
    (stroke (width 0) (type default))
  )
  (wire (pts (xy 342.265 137.16) (xy 342.265 140.335))
    (stroke (width 0) (type default))
  )
  (wire (pts (xy 367.03 53.975) (xy 367.03 52.07))
    (stroke (width 0) (type default))
  )
  (wire (pts (xy 102.235 156.21) (xy 102.235 154.94))
    (stroke (width 0) (type default))
  )
  (wire (pts (xy 41.275 40.64) (xy 36.195 40.64))
    (stroke (width 0) (type default))
  )
  (wire (pts (xy 185.42 194.31) (xy 186.69 194.31))
    (stroke (width 0) (type default))
  )
  (wire (pts (xy 241.3 41.91) (xy 254.508 41.91))
    (stroke (width 0) (type default))
  )
  (wire (pts (xy 275.082 51.308) (xy 284.48 51.308))
    (stroke (width 0) (type default))
  )
  (wire (pts (xy 229.87 264.16) (xy 262.89 264.16))
    (stroke (width 0) (type default))
  )
  (wire (pts (xy 51.308 177.8) (xy 51.308 180.34))
    (stroke (width 0) (type default))
  )
  (wire (pts (xy 100.965 59.69) (xy 100.965 57.15))
    (stroke (width 0) (type default))
  )
  (wire (pts (xy 43.18 50.8) (xy 44.45 50.8))
    (stroke (width 0) (type default))
  )
  (wire (pts (xy 308.61 50.8) (xy 309.88 50.8))
    (stroke (width 0) (type default))
  )
  (wire (pts (xy 165.1 269.24) (xy 166.878 269.24))
    (stroke (width 0) (type default))
  )
  (wire (pts (xy 219.71 261.62) (xy 218.44 261.62))
    (stroke (width 0) (type default))
  )
  (wire (pts (xy 38.735 55.88) (xy 38.735 50.8))
    (stroke (width 0) (type default))
  )
  (wire (pts (xy 22.86 100.965) (xy 22.86 99.695))
    (stroke (width 0) (type default))
  )
  (wire (pts (xy 51.308 203.2) (xy 51.308 205.74))
    (stroke (width 0) (type default))
  )
  (wire (pts (xy 363.22 158.75) (xy 356.87 158.75))
    (stroke (width 0) (type default))
  )
  (wire (pts (xy 94.615 116.84) (xy 87.63 116.84))
    (stroke (width 0) (type default))
  )
  (wire (pts (xy 218.44 264.16) (xy 218.44 266.7))
    (stroke (width 0) (type default))
  )
  (wire (pts (xy 352.425 137.16) (xy 361.95 137.16))
    (stroke (width 0) (type default))
  )
  (wire (pts (xy 185.42 219.075) (xy 185.42 217.17))
    (stroke (width 0) (type default))
  )
  (wire (pts (xy 246.38 164.465) (xy 246.38 163.83))
    (stroke (width 0) (type default))
  )
  (wire (pts (xy 338.455 48.26) (xy 328.93 48.26))
    (stroke (width 0) (type default))
  )
  (wire (pts (xy 159.385 46.355) (xy 159.385 43.815))
    (stroke (width 0) (type default))
  )
  (wire (pts (xy 53.34 100.965) (xy 62.865 100.965))
    (stroke (width 0) (type default))
  )
  (wire (pts (xy 22.86 100.965) (xy 22.86 104.775))
    (stroke (width 0) (type default))
  )
  (wire (pts (xy 267.97 252.095) (xy 267.97 253.365))
    (stroke (width 0) (type default))
  )
  (wire (pts (xy 59.69 48.26) (xy 69.215 48.26))
    (stroke (width 0) (type default))
  )
  (wire (pts (xy 219.71 259.08) (xy 218.44 259.08))
    (stroke (width 0) (type default))
  )
  (wire (pts (xy 172.72 140.97) (xy 186.69 140.97))
    (stroke (width 0) (type default))
  )
  (polyline (pts (xy 132.08 105.41) (xy 132.08 128.27))
    (stroke (width 0) (type default))
  )

  (wire (pts (xy 186.69 166.37) (xy 172.72 166.37))
    (stroke (width 0) (type default))
  )
  (wire (pts (xy 41.783 203.2) (xy 51.308 203.2))
    (stroke (width 0) (type default))
  )
  (wire (pts (xy 233.68 41.91) (xy 241.3 41.91))
    (stroke (width 0) (type default))
  )
  (wire (pts (xy 316.23 137.16) (xy 316.23 148.59))
    (stroke (width 0) (type default))
  )
  (wire (pts (xy 46.355 40.64) (xy 52.07 40.64))
    (stroke (width 0) (type default))
  )
  (polyline (pts (xy 77.47 134.62) (xy 142.24 134.62))
    (stroke (width 0) (type default))
  )

  (wire (pts (xy 227.33 182.88) (xy 251.46 182.88))
    (stroke (width 0) (type default))
  )
  (polyline (pts (xy 12.7 87.63) (xy 260.35 87.63))
    (stroke (width 0) (type default))
  )

  (wire (pts (xy 220.98 48.26) (xy 220.98 49.53))
    (stroke (width 0) (type default))
  )
  (wire (pts (xy 229.87 266.7) (xy 265.43 266.7))
    (stroke (width 0) (type default))
  )
  (wire (pts (xy 24.892 177.8) (xy 36.068 177.8))
    (stroke (width 0) (type default))
  )
  (wire (pts (xy 99.695 121.92) (xy 121.92 121.92))
    (stroke (width 0) (type default))
  )
  (wire (pts (xy 334.01 107.315) (xy 334.01 109.855))
    (stroke (width 0) (type default))
  )
  (wire (pts (xy 51.308 151.13) (xy 51.308 153.67))
    (stroke (width 0) (type default))
  )
  (wire (pts (xy 265.43 252.095) (xy 265.43 266.7))
    (stroke (width 0) (type default))
  )
  (wire (pts (xy 38.1 124.46) (xy 38.1 123.19))
    (stroke (width 0) (type default))
  )
  (polyline (pts (xy 199.39 234.95) (xy 199.39 284.48))
    (stroke (width 0) (type default))
  )

  (wire (pts (xy 102.235 40.005) (xy 103.505 40.005))
    (stroke (width 0) (type default))
  )
  (wire (pts (xy 172.72 115.57) (xy 186.69 115.57))
    (stroke (width 0) (type default))
  )
  (wire (pts (xy 299.085 89.535) (xy 309.88 89.535))
    (stroke (width 0) (type default))
  )
  (wire (pts (xy 36.195 55.88) (xy 38.735 55.88))
    (stroke (width 0) (type default))
  )
  (wire (pts (xy 132.588 261.62) (xy 132.588 265.43))
    (stroke (width 0) (type default))
  )
  (wire (pts (xy 291.084 104.775) (xy 302.26 104.775))
    (stroke (width 0) (type default))
  )
  (wire (pts (xy 53.34 100.965) (xy 53.34 104.775))
    (stroke (width 0) (type default))
  )
  (wire (pts (xy 227.33 158.75) (xy 247.65 158.75))
    (stroke (width 0) (type default))
  )
  (wire (pts (xy 99.695 116.84) (xy 121.92 116.84))
    (stroke (width 0) (type default))
  )
  (wire (pts (xy 297.18 198.12) (xy 297.18 200.66))
    (stroke (width 0) (type default))
  )
  (wire (pts (xy 308.61 58.42) (xy 309.88 58.42))
    (stroke (width 0) (type default))
  )
  (wire (pts (xy 123.063 261.62) (xy 132.588 261.62))
    (stroke (width 0) (type default))
  )
  (wire (pts (xy 227.33 213.36) (xy 251.206 213.36))
    (stroke (width 0) (type default))
  )
  (wire (pts (xy 316.23 137.16) (xy 319.405 137.16))
    (stroke (width 0) (type default))
  )
  (wire (pts (xy 36.195 43.18) (xy 41.275 43.18))
    (stroke (width 0) (type default))
  )
  (wire (pts (xy 38.1 100.965) (xy 38.1 104.775))
    (stroke (width 0) (type default))
  )
  (wire (pts (xy 298.45 66.04) (xy 309.88 66.04))
    (stroke (width 0) (type default))
  )
  (wire (pts (xy 159.385 56.515) (xy 159.385 53.975))
    (stroke (width 0) (type default))
  )
  (wire (pts (xy 291.338 99.695) (xy 309.88 99.695))
    (stroke (width 0) (type default))
  )
  (wire (pts (xy 328.93 60.96) (xy 332.74 60.96))
    (stroke (width 0) (type default))
  )
  (wire (pts (xy 172.72 148.59) (xy 186.69 148.59))
    (stroke (width 0) (type default))
  )
  (wire (pts (xy 123.19 34.925) (xy 131.445 34.925))
    (stroke (width 0) (type default))
  )
  (polyline (pts (xy 132.08 110.49) (xy 88.9 110.49))
    (stroke (width 0) (type default))
  )

  (wire (pts (xy 142.748 271.78) (xy 144.78 271.78))
    (stroke (width 0) (type default))
  )
  (wire (pts (xy 298.45 55.88) (xy 308.61 55.88))
    (stroke (width 0) (type default))
  )
  (wire (pts (xy 177.038 264.16) (xy 177.038 258.445))
    (stroke (width 0) (type default))
  )
  (wire (pts (xy 45.72 124.46) (xy 45.72 123.19))
    (stroke (width 0) (type default))
  )
  (wire (pts (xy 241.3 40.64) (xy 241.3 41.91))
    (stroke (width 0) (type default))
  )
  (wire (pts (xy 227.33 115.57) (xy 251.46 115.57))
    (stroke (width 0) (type default))
  )
  (wire (pts (xy 22.86 123.19) (xy 22.86 121.92))
    (stroke (width 0) (type default))
  )
  (wire (pts (xy 315.595 184.15) (xy 325.247 184.15))
    (stroke (width 0) (type default))
  )
  (wire (pts (xy 298.45 60.96) (xy 309.88 60.96))
    (stroke (width 0) (type default))
  )
  (wire (pts (xy 328.93 66.04) (xy 332.74 66.04))
    (stroke (width 0) (type default))
  )
  (polyline (pts (xy 187.96 87.63) (xy 187.96 15.24))
    (stroke (width 0) (type default))
  )

  (wire (pts (xy 219.71 264.16) (xy 218.44 264.16))
    (stroke (width 0) (type default))
  )
  (wire (pts (xy 297.815 193.04) (xy 297.18 193.04))
    (stroke (width 0) (type default))
  )
  (wire (pts (xy 224.282 30.734) (xy 233.68 30.734))
    (stroke (width 0) (type default))
  )
  (wire (pts (xy 219.71 271.78) (xy 215.9 271.78))
    (stroke (width 0) (type default))
  )
  (wire (pts (xy 41.148 177.8) (xy 51.308 177.8))
    (stroke (width 0) (type default))
  )
  (polyline (pts (xy 77.47 12.7) (xy 77.47 234.95))
    (stroke (width 0) (type default))
  )

  (wire (pts (xy 54.61 33.02) (xy 68.58 33.02))
    (stroke (width 0) (type default))
  )
  (wire (pts (xy 33.655 222.377) (xy 37.465 222.377))
    (stroke (width 0) (type default))
  )
  (wire (pts (xy 185.42 212.09) (xy 186.69 212.09))
    (stroke (width 0) (type default))
  )
  (wire (pts (xy 54.61 33.02) (xy 54.61 34.29))
    (stroke (width 0) (type default))
  )
  (wire (pts (xy 309.88 68.58) (xy 307.34 68.58))
    (stroke (width 0) (type default))
  )
  (wire (pts (xy 180.848 266.7) (xy 196.85 266.7))
    (stroke (width 0) (type default))
  )
  (wire (pts (xy 284.48 148.59) (xy 298.45 148.59))
    (stroke (width 0) (type default))
  )
  (wire (pts (xy 165.1 261.62) (xy 187.198 261.62))
    (stroke (width 0) (type default))
  )
  (wire (pts (xy 218.44 269.24) (xy 219.71 269.24))
    (stroke (width 0) (type default))
  )
  (wire (pts (xy 306.705 94.615) (xy 309.88 94.615))
    (stroke (width 0) (type default))
  )
  (wire (pts (xy 309.88 97.155) (xy 306.705 97.155))
    (stroke (width 0) (type default))
  )
  (wire (pts (xy 168.275 53.975) (xy 168.275 51.435))
    (stroke (width 0) (type default))
  )
  (bus (pts (xy 165.1 148.59) (xy 168.91 148.59))
    (stroke (width 0) (type default))
  )

  (polyline (pts (xy 107.95 105.41) (xy 107.95 128.27))
    (stroke (width 0) (type default))
  )

  (wire (pts (xy 93.98 57.15) (xy 93.98 59.055))
    (stroke (width 0) (type default))
  )
  (wire (pts (xy 93.98 57.15) (xy 100.965 57.15))
    (stroke (width 0) (type default))
  )
  (wire (pts (xy 227.33 123.19) (xy 251.46 123.19))
    (stroke (width 0) (type default))
  )
  (wire (pts (xy 51.308 177.8) (xy 60.452 177.8))
    (stroke (width 0) (type default))
  )
  (wire (pts (xy 53.34 123.19) (xy 53.34 124.46))
    (stroke (width 0) (type default))
  )
  (wire (pts (xy 219.71 256.54) (xy 218.44 256.54))
    (stroke (width 0) (type default))
  )
  (wire (pts (xy 187.198 251.46) (xy 187.198 253.365))
    (stroke (width 0) (type default))
  )
  (wire (pts (xy 262.255 184.785) (xy 271.78 184.785))
    (stroke (width 0) (type default))
  )
  (wire (pts (xy 103.505 37.465) (xy 102.235 37.465))
    (stroke (width 0) (type default))
  )
  (wire (pts (xy 356.87 154.94) (xy 356.87 158.75))
    (stroke (width 0) (type default))
  )
  (wire (pts (xy 36.195 50.8) (xy 38.735 50.8))
    (stroke (width 0) (type default))
  )
  (wire (pts (xy 176.403 269.24) (xy 180.848 269.24))
    (stroke (width 0) (type default))
  )
  (wire (pts (xy 171.45 153.67) (xy 186.69 153.67))
    (stroke (width 0) (type default))
  )
  (wire (pts (xy 44.45 53.34) (xy 41.91 53.34))
    (stroke (width 0) (type default))
  )
  (wire (pts (xy 166.878 258.445) (xy 166.878 269.24))
    (stroke (width 0) (type default))
  )
  (wire (pts (xy 330.2 90.805) (xy 330.2 89.535))
    (stroke (width 0) (type default))
  )
  (wire (pts (xy 218.44 261.62) (xy 218.44 264.16))
    (stroke (width 0) (type default))
  )
  (wire (pts (xy 187.198 251.46) (xy 196.85 251.46))
    (stroke (width 0) (type default))
  )
  (wire (pts (xy 41.91 50.8) (xy 38.735 50.8))
    (stroke (width 0) (type default))
  )
  (wire (pts (xy 51.308 153.67) (xy 51.308 156.21))
    (stroke (width 0) (type default))
  )
  (wire (pts (xy 36.195 35.56) (xy 39.37 35.56))
    (stroke (width 0) (type default))
  )
  (wire (pts (xy 37.465 53.34) (xy 37.465 48.26))
    (stroke (width 0) (type default))
  )
  (wire (pts (xy 38.1 71.12) (xy 36.195 71.12))
    (stroke (width 0) (type default))
  )
  (wire (pts (xy 182.245 161.29) (xy 186.69 161.29))
    (stroke (width 0) (type default))
  )
  (wire (pts (xy 218.44 256.54) (xy 218.44 259.08))
    (stroke (width 0) (type default))
  )
  (wire (pts (xy 284.48 154.94) (xy 298.45 154.94))
    (stroke (width 0) (type default))
  )
  (wire (pts (xy 45.085 230.759) (xy 56.515 230.759))
    (stroke (width 0) (type default))
  )
  (wire (pts (xy 316.865 198.12) (xy 315.595 198.12))
    (stroke (width 0) (type default))
  )
  (wire (pts (xy 316.865 198.12) (xy 316.865 200.66))
    (stroke (width 0) (type default))
  )
  (wire (pts (xy 142.748 273.812) (xy 142.748 271.78))
    (stroke (width 0) (type default))
  )
  (wire (pts (xy 30.48 124.46) (xy 30.48 123.19))
    (stroke (width 0) (type default))
  )
  (wire (pts (xy 161.925 161.29) (xy 177.165 161.29))
    (stroke (width 0) (type default))
  )
  (wire (pts (xy 342.265 137.16) (xy 352.425 137.16))
    (stroke (width 0) (type default))
  )
  (wire (pts (xy 172.72 182.88) (xy 186.69 182.88))
    (stroke (width 0) (type default))
  )
  (wire (pts (xy 262.89 252.095) (xy 262.89 264.16))
    (stroke (width 0) (type default))
  )
  (wire (pts (xy 165.1 266.7) (xy 180.848 266.7))
    (stroke (width 0) (type default))
  )
  (wire (pts (xy 246.38 163.83) (xy 247.65 163.83))
    (stroke (width 0) (type default))
  )
  (wire (pts (xy 297.18 160.02) (xy 297.18 157.48))
    (stroke (width 0) (type default))
  )
  (wire (pts (xy 361.315 163.83) (xy 361.315 162.56))
    (stroke (width 0) (type default))
  )
  (wire (pts (xy 218.44 266.7) (xy 218.44 269.24))
    (stroke (width 0) (type default))
  )
  (wire (pts (xy 220.98 49.53) (xy 226.06 49.53))
    (stroke (width 0) (type default))
  )
  (wire (pts (xy 307.34 68.58) (xy 307.34 71.12))
    (stroke (width 0) (type default))
  )
  (wire (pts (xy 30.48 100.965) (xy 30.48 104.775))
    (stroke (width 0) (type default))
  )
  (wire (pts (xy 217.17 55.88) (xy 217.17 49.53))
    (stroke (width 0) (type default))
  )
  (wire (pts (xy 41.783 153.67) (xy 51.308 153.67))
    (stroke (width 0) (type default))
  )
  (wire (pts (xy 165.735 53.975) (xy 168.275 53.975))
    (stroke (width 0) (type default))
  )
  (wire (pts (xy 218.44 269.24) (xy 218.44 274.32))
    (stroke (width 0) (type default))
  )
  (wire (pts (xy 70.358 123.19) (xy 60.96 123.19))
    (stroke (width 0) (type default))
  )
  (wire (pts (xy 142.748 271.78) (xy 142.748 269.24))
    (stroke (width 0) (type default))
  )
  (wire (pts (xy 97.79 34.925) (xy 102.235 34.925))
    (stroke (width 0) (type default))
  )
  (wire (pts (xy 231.14 128.27) (xy 251.46 128.27))
    (stroke (width 0) (type default))
  )
  (wire (pts (xy 330.2 50.8) (xy 330.2 52.07))
    (stroke (width 0) (type default))
  )
  (wire (pts (xy 60.96 123.19) (xy 53.34 123.19))
    (stroke (width 0) (type default))
  )
  (wire (pts (xy 328.93 107.315) (xy 334.01 107.315))
    (stroke (width 0) (type default))
  )
  (wire (pts (xy 298.45 63.5) (xy 309.88 63.5))
    (stroke (width 0) (type default))
  )
  (wire (pts (xy 298.45 50.8) (xy 308.61 50.8))
    (stroke (width 0) (type default))
  )
  (wire (pts (xy 186.69 168.91) (xy 172.72 168.91))
    (stroke (width 0) (type default))
  )
  (wire (pts (xy 227.33 130.81) (xy 251.46 130.81))
    (stroke (width 0) (type default))
  )
  (wire (pts (xy 185.42 217.17) (xy 185.42 214.63))
    (stroke (width 0) (type default))
  )
  (bus (pts (xy 168.91 148.59) (xy 168.91 151.13))
    (stroke (width 0) (type default))
  )

  (wire (pts (xy 217.17 49.53) (xy 220.98 49.53))
    (stroke (width 0) (type default))
  )
  (wire (pts (xy 271.78 184.785) (xy 271.78 186.055))
    (stroke (width 0) (type default))
  )
  (bus (pts (xy 168.91 151.13) (xy 168.91 153.67))
    (stroke (width 0) (type default))
  )

  (wire (pts (xy 185.42 214.63) (xy 186.69 214.63))
    (stroke (width 0) (type default))
  )
  (wire (pts (xy 265.684 94.615) (xy 274.32 94.615))
    (stroke (width 0) (type default))
  )
  (wire (pts (xy 185.42 212.09) (xy 185.42 214.63))
    (stroke (width 0) (type default))
  )
  (wire (pts (xy 227.33 139.7) (xy 251.46 139.7))
    (stroke (width 0) (type default))
  )
  (wire (pts (xy 378.46 152.4) (xy 381 152.4))
    (stroke (width 0) (type default))
  )
  (wire (pts (xy 281.94 190.5) (xy 297.815 190.5))
    (stroke (width 0) (type default))
  )
  (wire (pts (xy 326.39 190.5) (xy 315.595 190.5))
    (stroke (width 0) (type default))
  )
  (wire (pts (xy 172.72 177.8) (xy 186.69 177.8))
    (stroke (width 0) (type default))
  )
  (wire (pts (xy 308.61 53.34) (xy 309.88 53.34))
    (stroke (width 0) (type default))
  )
  (polyline (pts (xy 120.65 234.95) (xy 120.65 284.48))
    (stroke (width 0) (type default))
  )

  (wire (pts (xy 227.33 120.65) (xy 251.46 120.65))
    (stroke (width 0) (type default))
  )
  (polyline (pts (xy 88.9 128.27) (xy 132.08 128.27))
    (stroke (width 0) (type default))
  )

  (wire (pts (xy 95.885 154.94) (xy 102.235 154.94))
    (stroke (width 0) (type default))
  )
  (wire (pts (xy 187.198 261.62) (xy 196.85 261.62))
    (stroke (width 0) (type default))
  )
  (wire (pts (xy 308.61 55.88) (xy 309.88 55.88))
    (stroke (width 0) (type default))
  )
  (wire (pts (xy 328.93 104.775) (xy 336.55 104.775))
    (stroke (width 0) (type default))
  )
  (wire (pts (xy 227.33 128.27) (xy 231.14 128.27))
    (stroke (width 0) (type default))
  )
  (wire (pts (xy 30.48 100.965) (xy 38.1 100.965))
    (stroke (width 0) (type default))
  )
  (wire (pts (xy 358.14 93.98) (xy 360.045 93.98))
    (stroke (width 0) (type default))
  )
  (wire (pts (xy 231.775 243.84) (xy 238.76 243.84))
    (stroke (width 0) (type default))
  )
  (wire (pts (xy 349.885 185.42) (xy 351.79 185.42))
    (stroke (width 0) (type default))
  )
  (wire (pts (xy 142.748 269.24) (xy 144.78 269.24))
    (stroke (width 0) (type default))
  )
  (wire (pts (xy 185.42 194.31) (xy 185.42 204.47))
    (stroke (width 0) (type default))
  )
  (wire (pts (xy 41.91 53.34) (xy 41.91 50.8))
    (stroke (width 0) (type default))
  )
  (wire (pts (xy 37.465 48.26) (xy 44.45 48.26))
    (stroke (width 0) (type default))
  )
  (wire (pts (xy 360.045 93.98) (xy 360.045 95.885))
    (stroke (width 0) (type default))
  )
  (wire (pts (xy 123.19 36.83) (xy 123.19 34.925))
    (stroke (width 0) (type default))
  )
  (polyline (pts (xy 132.08 105.41) (xy 88.9 105.41))
    (stroke (width 0) (type default))
  )

  (wire (pts (xy 342.265 145.415) (xy 342.265 154.94))
    (stroke (width 0) (type default))
  )
  (wire (pts (xy 274.32 94.615) (xy 274.32 96.52))
    (stroke (width 0) (type default))
  )
  (wire (pts (xy 46.355 43.18) (xy 52.07 43.18))
    (stroke (width 0) (type default))
  )
  (wire (pts (xy 60.96 123.19) (xy 60.96 124.46))
    (stroke (width 0) (type default))
  )
  (polyline (pts (xy 299.72 234.95) (xy 299.72 252.73))
    (stroke (width 0) (type default))
  )

  (wire (pts (xy 284.48 51.308) (xy 284.48 52.705))
    (stroke (width 0) (type default))
  )
  (wire (pts (xy 22.86 100.965) (xy 30.48 100.965))
    (stroke (width 0) (type default))
  )
  (wire (pts (xy 321.31 220.98) (xy 321.31 223.52))
    (stroke (width 0) (type default))
  )
  (wire (pts (xy 297.18 157.48) (xy 284.48 157.48))
    (stroke (width 0) (type default))
  )
  (wire (pts (xy 24.384 153.67) (xy 36.703 153.67))
    (stroke (width 0) (type default))
  )
  (wire (pts (xy 103.505 59.69) (xy 100.965 59.69))
    (stroke (width 0) (type default))
  )
  (wire (pts (xy 54.61 39.37) (xy 54.61 40.64))
    (stroke (width 0) (type default))
  )
  (wire (pts (xy 191.262 60.96) (xy 204.47 60.96))
    (stroke (width 0) (type default))
  )
  (wire (pts (xy 123.19 59.055) (xy 123.19 57.15))
    (stroke (width 0) (type default))
  )
  (wire (pts (xy 229.87 256.54) (xy 231.775 256.54))
    (stroke (width 0) (type default))
  )
  (wire (pts (xy 123.19 34.925) (xy 118.745 34.925))
    (stroke (width 0) (type default))
  )
  (wire (pts (xy 132.588 261.62) (xy 144.78 261.62))
    (stroke (width 0) (type default))
  )
  (wire (pts (xy 184.785 127) (xy 186.69 127))
    (stroke (width 0) (type default))
  )
  (wire (pts (xy 30.48 123.19) (xy 38.1 123.19))
    (stroke (width 0) (type default))
  )
  (wire (pts (xy 294.894 228.6) (xy 313.69 228.6))
    (stroke (width 0) (type default))
  )
  (wire (pts (xy 39.37 33.02) (xy 54.61 33.02))
    (stroke (width 0) (type default))
  )
  (wire (pts (xy 229.87 259.08) (xy 257.81 259.08))
    (stroke (width 0) (type default))
  )
  (wire (pts (xy 39.37 35.56) (xy 39.37 33.02))
    (stroke (width 0) (type default))
  )
  (wire (pts (xy 219.71 266.7) (xy 218.44 266.7))
    (stroke (width 0) (type default))
  )
  (wire (pts (xy 306.705 97.155) (xy 306.705 111.76))
    (stroke (width 0) (type default))
  )
  (wire (pts (xy 328.93 63.5) (xy 332.74 63.5))
    (stroke (width 0) (type default))
  )
  (wire (pts (xy 319.405 137.16) (xy 319.405 140.335))
    (stroke (width 0) (type default))
  )
  (wire (pts (xy 159.385 53.975) (xy 159.385 51.435))
    (stroke (width 0) (type default))
  )
  (wire (pts (xy 319.405 137.16) (xy 339.725 137.16))
    (stroke (width 0) (type default))
  )
  (wire (pts (xy 229.87 261.62) (xy 260.35 261.62))
    (stroke (width 0) (type default))
  )
  (wire (pts (xy 381 158.75) (xy 378.46 158.75))
    (stroke (width 0) (type default))
  )
  (wire (pts (xy 297.18 193.04) (xy 297.18 198.12))
    (stroke (width 0) (type default))
  )
  (wire (pts (xy 361.95 148.59) (xy 361.95 137.16))
    (stroke (width 0) (type default))
  )
  (wire (pts (xy 231.14 128.27) (xy 231.14 113.03))
    (stroke (width 0) (type default))
  )
  (wire (pts (xy 185.42 217.17) (xy 186.69 217.17))
    (stroke (width 0) (type default))
  )
  (wire (pts (xy 186.69 130.81) (xy 184.785 130.81))
    (stroke (width 0) (type default))
  )
  (wire (pts (xy 102.235 154.94) (xy 106.68 154.94))
    (stroke (width 0) (type default))
  )
  (wire (pts (xy 298.45 48.26) (xy 309.88 48.26))
    (stroke (width 0) (type default))
  )
  (polyline (pts (xy 77.47 177.292) (xy 142.24 177.292))
    (stroke (width 0) (type default))
  )

  (wire (pts (xy 177.038 253.365) (xy 177.038 251.46))
    (stroke (width 0) (type default))
  )
  (wire (pts (xy 302.26 104.775) (xy 309.88 104.775))
    (stroke (width 0) (type default))
  )
  (wire (pts (xy 298.45 157.48) (xy 297.18 157.48))
    (stroke (width 0) (type default))
  )
  (wire (pts (xy 217.17 49.53) (xy 217.17 45.72))
    (stroke (width 0) (type default))
  )
  (wire (pts (xy 83.82 57.15) (xy 93.98 57.15))
    (stroke (width 0) (type default))
  )
  (wire (pts (xy 284.48 162.56) (xy 298.45 162.56))
    (stroke (width 0) (type default))
  )
  (wire (pts (xy 316.23 152.4) (xy 339.725 152.4))
    (stroke (width 0) (type default))
  )
  (wire (pts (xy 308.61 55.88) (xy 308.61 58.42))
    (stroke (width 0) (type default))
  )
  (wire (pts (xy 123.19 57.15) (xy 132.08 57.15))
    (stroke (width 0) (type default))
  )
  (wire (pts (xy 52.07 40.64) (xy 54.61 40.64))
    (stroke (width 0) (type default))
  )
  (wire (pts (xy 227.33 118.11) (xy 251.46 118.11))
    (stroke (width 0) (type default))
  )
  (wire (pts (xy 342.265 154.94) (xy 356.87 154.94))
    (stroke (width 0) (type default))
  )
  (wire (pts (xy 114.3 154.94) (xy 116.84 154.94))
    (stroke (width 0) (type default))
  )
  (wire (pts (xy 102.235 34.925) (xy 103.505 34.925))
    (stroke (width 0) (type default))
  )
  (wire (pts (xy 184.785 130.81) (xy 184.785 127))
    (stroke (width 0) (type default))
  )
  (wire (pts (xy 36.195 76.835) (xy 38.1 76.835))
    (stroke (width 0) (type default))
  )
  (wire (pts (xy 102.235 64.135) (xy 102.235 62.23))
    (stroke (width 0) (type default))
  )
  (wire (pts (xy 302.26 104.775) (xy 302.26 106.68))
    (stroke (width 0) (type default))
  )
  (wire (pts (xy 56.515 226.695) (xy 69.469 226.695))
    (stroke (width 0) (type default))
  )
  (wire (pts (xy 100.965 57.15) (xy 103.505 57.15))
    (stroke (width 0) (type default))
  )
  (wire (pts (xy 351.79 185.42) (xy 351.79 187.325))
    (stroke (width 0) (type default))
  )
  (wire (pts (xy 42.545 68.58) (xy 36.195 68.58))
    (stroke (width 0) (type default))
  )
  (wire (pts (xy 43.18 50.8) (xy 43.18 53.975))
    (stroke (width 0) (type default))
  )
  (wire (pts (xy 36.195 53.34) (xy 37.465 53.34))
    (stroke (width 0) (type default))
  )
  (wire (pts (xy 231.775 243.84) (xy 231.775 256.54))
    (stroke (width 0) (type default))
  )
  (wire (pts (xy 42.545 72.39) (xy 42.545 68.58))
    (stroke (width 0) (type default))
  )
  (wire (pts (xy 168.275 53.975) (xy 182.245 53.975))
    (stroke (width 0) (type default))
  )
  (wire (pts (xy 102.235 62.23) (xy 103.505 62.23))
    (stroke (width 0) (type default))
  )
  (wire (pts (xy 367.03 52.07) (xy 365.125 52.07))
    (stroke (width 0) (type default))
  )
  (wire (pts (xy 36.195 48.26) (xy 37.465 48.26))
    (stroke (width 0) (type default))
  )
  (wire (pts (xy 217.17 37.465) (xy 217.17 40.64))
    (stroke (width 0) (type default))
  )
  (wire (pts (xy 51.308 177.8) (xy 51.308 175.26))
    (stroke (width 0) (type default))
  )
  (wire (pts (xy 328.93 102.235) (xy 334.01 102.235))
    (stroke (width 0) (type default))
  )
  (wire (pts (xy 328.93 99.695) (xy 336.55 99.695))
    (stroke (width 0) (type default))
  )
  (wire (pts (xy 217.17 49.53) (xy 204.978 49.53))
    (stroke (width 0) (type default))
  )
  (wire (pts (xy 166.878 251.46) (xy 177.038 251.46))
    (stroke (width 0) (type default))
  )
  (wire (pts (xy 165.735 53.975) (xy 165.735 56.515))
    (stroke (width 0) (type default))
  )
  (wire (pts (xy 238.76 245.11) (xy 238.76 243.84))
    (stroke (width 0) (type default))
  )
  (wire (pts (xy 222.25 106.045) (xy 231.14 106.045))
    (stroke (width 0) (type default))
  )
  (wire (pts (xy 186.69 123.19) (xy 172.72 123.19))
    (stroke (width 0) (type default))
  )
  (wire (pts (xy 238.76 243.84) (xy 243.205 243.84))
    (stroke (width 0) (type default))
  )
  (wire (pts (xy 363.22 148.59) (xy 361.95 148.59))
    (stroke (width 0) (type default))
  )
  (wire (pts (xy 38.1 100.965) (xy 45.72 100.965))
    (stroke (width 0) (type default))
  )
  (polyline (pts (xy 260.35 87.63) (xy 260.35 15.24))
    (stroke (width 0) (type default))
  )

  (wire (pts (xy 317.5 162.56) (xy 316.23 162.56))
    (stroke (width 0) (type default))
  )
  (wire (pts (xy 94.615 121.92) (xy 87.63 121.92))
    (stroke (width 0) (type default))
  )
  (wire (pts (xy 229.87 271.78) (xy 241.808 271.78))
    (stroke (width 0) (type default))
  )
  (polyline (pts (xy 12.7 234.95) (xy 299.72 234.95))
    (stroke (width 0) (type default))
  )

  (wire (pts (xy 278.13 149.225) (xy 278.13 151.13))
    (stroke (width 0) (type default))
  )
  (wire (pts (xy 339.725 152.4) (xy 363.22 152.4))
    (stroke (width 0) (type default))
  )
  (wire (pts (xy 231.14 107.95) (xy 231.14 106.045))
    (stroke (width 0) (type default))
  )
  (wire (pts (xy 45.72 100.965) (xy 53.34 100.965))
    (stroke (width 0) (type default))
  )
  (wire (pts (xy 204.47 60.96) (xy 209.55 60.96))
    (stroke (width 0) (type default))
  )
  (wire (pts (xy 227.33 133.35) (xy 251.46 133.35))
    (stroke (width 0) (type default))
  )
  (wire (pts (xy 284.48 152.4) (xy 298.45 152.4))
    (stroke (width 0) (type default))
  )
  (wire (pts (xy 45.085 222.377) (xy 56.515 222.377))
    (stroke (width 0) (type default))
  )
  (wire (pts (xy 51.308 203.2) (xy 59.69 203.2))
    (stroke (width 0) (type default))
  )
  (polyline (pts (xy 142.24 177.292) (xy 142.24 15.24))
    (stroke (width 0) (type default))
  )

  (wire (pts (xy 330.2 89.535) (xy 328.93 89.535))
    (stroke (width 0) (type default))
  )
  (wire (pts (xy 361.315 162.56) (xy 363.22 162.56))
    (stroke (width 0) (type default))
  )
  (wire (pts (xy 339.725 137.16) (xy 339.725 140.335))
    (stroke (width 0) (type default))
  )
  (wire (pts (xy 208.026 37.465) (xy 217.17 37.465))
    (stroke (width 0) (type default))
  )
  (wire (pts (xy 60.706 153.67) (xy 51.308 153.67))
    (stroke (width 0) (type default))
  )
  (wire (pts (xy 159.385 53.975) (xy 165.735 53.975))
    (stroke (width 0) (type default))
  )
  (wire (pts (xy 187.198 261.62) (xy 187.198 258.445))
    (stroke (width 0) (type default))
  )
  (wire (pts (xy 306.705 94.615) (xy 306.705 97.155))
    (stroke (width 0) (type default))
  )
  (wire (pts (xy 257.81 259.08) (xy 269.875 259.08))
    (stroke (width 0) (type default))
  )
  (wire (pts (xy 165.1 264.16) (xy 177.038 264.16))
    (stroke (width 0) (type default))
  )
  (wire (pts (xy 321.31 220.98) (xy 327.66 220.98))
    (stroke (width 0) (type default))
  )
  (wire (pts (xy 102.235 37.465) (xy 102.235 34.925))
    (stroke (width 0) (type default))
  )
  (wire (pts (xy 54.61 40.64) (xy 54.61 41.91))
    (stroke (width 0) (type default))
  )
  (wire (pts (xy 233.68 33.655) (xy 233.68 30.734))
    (stroke (width 0) (type default))
  )
  (wire (pts (xy 59.69 53.34) (xy 69.215 53.34))
    (stroke (width 0) (type default))
  )
  (wire (pts (xy 25.146 203.2) (xy 36.703 203.2))
    (stroke (width 0) (type default))
  )
  (wire (pts (xy 110.49 161.29) (xy 110.49 160.02))
    (stroke (width 0) (type default))
  )
  (wire (pts (xy 328.93 50.8) (xy 330.2 50.8))
    (stroke (width 0) (type default))
  )
  (wire (pts (xy 171.45 156.21) (xy 186.69 156.21))
    (stroke (width 0) (type default))
  )
  (wire (pts (xy 102.235 41.91) (xy 102.235 40.005))
    (stroke (width 0) (type default))
  )
  (wire (pts (xy 45.72 100.965) (xy 45.72 104.775))
    (stroke (width 0) (type default))
  )
  (wire (pts (xy 157.48 43.815) (xy 159.385 43.815))
    (stroke (width 0) (type default))
  )
  (wire (pts (xy 281.94 184.15) (xy 297.815 184.15))
    (stroke (width 0) (type default))
  )
  (wire (pts (xy 172.72 120.65) (xy 186.69 120.65))
    (stroke (width 0) (type default))
  )
  (wire (pts (xy 339.725 137.16) (xy 342.265 137.16))
    (stroke (width 0) (type default))
  )
  (wire (pts (xy 172.72 118.11) (xy 186.69 118.11))
    (stroke (width 0) (type default))
  )
  (wire (pts (xy 172.72 143.51) (xy 186.69 143.51))
    (stroke (width 0) (type default))
  )
  (wire (pts (xy 166.878 253.365) (xy 166.878 251.46))
    (stroke (width 0) (type default))
  )
  (wire (pts (xy 180.848 269.24) (xy 180.848 266.7))
    (stroke (width 0) (type default))
  )
  (wire (pts (xy 334.01 102.235) (xy 334.01 107.315))
    (stroke (width 0) (type default))
  )
  (wire (pts (xy 177.038 251.46) (xy 187.198 251.46))
    (stroke (width 0) (type default))
  )
  (wire (pts (xy 116.84 154.94) (xy 116.84 156.21))
    (stroke (width 0) (type default))
  )
  (wire (pts (xy 298.45 160.02) (xy 297.18 160.02))
    (stroke (width 0) (type default))
  )
  (wire (pts (xy 265.43 266.7) (xy 269.875 266.7))
    (stroke (width 0) (type default))
  )
  (wire (pts (xy 51.308 203.2) (xy 51.308 200.66))
    (stroke (width 0) (type default))
  )
  (wire (pts (xy 326.39 187.96) (xy 315.595 187.96))
    (stroke (width 0) (type default))
  )
  (wire (pts (xy 45.72 123.19) (xy 53.34 123.19))
    (stroke (width 0) (type default))
  )
  (wire (pts (xy 297.18 198.12) (xy 297.815 198.12))
    (stroke (width 0) (type default))
  )
  (wire (pts (xy 260.35 252.095) (xy 260.35 261.62))
    (stroke (width 0) (type default))
  )
  (polyline (pts (xy 88.9 105.41) (xy 88.9 128.27))
    (stroke (width 0) (type default))
  )

  (wire (pts (xy 306.705 92.075) (xy 306.705 94.615))
    (stroke (width 0) (type default))
  )
  (wire (pts (xy 317.5 163.83) (xy 317.5 162.56))
    (stroke (width 0) (type default))
  )
  (wire (pts (xy 22.86 123.19) (xy 30.48 123.19))
    (stroke (width 0) (type default))
  )
  (wire (pts (xy 52.07 43.18) (xy 52.07 40.64))
    (stroke (width 0) (type default))
  )
  (wire (pts (xy 218.44 259.08) (xy 218.44 261.62))
    (stroke (width 0) (type default))
  )
  (wire (pts (xy 262.89 264.16) (xy 269.875 264.16))
    (stroke (width 0) (type default))
  )
  (wire (pts (xy 352.425 137.16) (xy 352.425 139.7))
    (stroke (width 0) (type default))
  )
  (wire (pts (xy 56.515 226.695) (xy 56.515 222.377))
    (stroke (width 0) (type default))
  )
  (wire (pts (xy 123.19 57.15) (xy 118.745 57.15))
    (stroke (width 0) (type default))
  )
  (wire (pts (xy 172.72 127) (xy 184.785 127))
    (stroke (width 0) (type default))
  )
  (wire (pts (xy 204.47 59.69) (xy 204.47 60.96))
    (stroke (width 0) (type default))
  )
  (wire (pts (xy 185.42 209.55) (xy 185.42 212.09))
    (stroke (width 0) (type default))
  )
  (wire (pts (xy 38.1 123.19) (xy 45.72 123.19))
    (stroke (width 0) (type default))
  )
  (wire (pts (xy 140.462 116.84) (xy 127 116.84))
    (stroke (width 0) (type default))
  )
  (wire (pts (xy 227.33 207.01) (xy 228.6 207.01))
    (stroke (width 0) (type default))
  )
  (wire (pts (xy 97.79 34.925) (xy 97.79 36.83))
    (stroke (width 0) (type default))
  )
  (wire (pts (xy 227.33 137.16) (xy 251.46 137.16))
    (stroke (width 0) (type default))
  )
  (wire (pts (xy 227.33 161.29) (xy 247.65 161.29))
    (stroke (width 0) (type default))
  )
  (wire (pts (xy 306.705 92.075) (xy 309.88 92.075))
    (stroke (width 0) (type default))
  )
  (wire (pts (xy 339.725 145.415) (xy 339.725 152.4))
    (stroke (width 0) (type default))
  )
  (wire (pts (xy 227.33 125.73) (xy 251.46 125.73))
    (stroke (width 0) (type default))
  )
  (wire (pts (xy 166.878 269.24) (xy 171.323 269.24))
    (stroke (width 0) (type default))
  )
  (wire (pts (xy 308.61 50.8) (xy 308.61 53.34))
    (stroke (width 0) (type default))
  )
  (wire (pts (xy 297.815 195.58) (xy 281.94 195.58))
    (stroke (width 0) (type default))
  )

  (text "Connector configuration" (at 81.28 93.98 0)
    (effects (font (size 2.54 2.54) (thickness 0.508) bold) (justify left bottom))
  )
  (text "USB-C VBUS\nvoltage divider" (at 143.51 22.86 0)
    (effects (font (size 2.54 2.54) (thickness 0.508) bold) (justify left bottom))
  )
  (text "A1 -> B" (at 301.625 167.64 0)
    (effects (font (size 1.27 1.27)) (justify left bottom))
  )
  (text "2 A -> B" (at 314.325 75.565 0)
    (effects (font (size 1.27 1.27)) (justify left bottom))
  )
  (text "FTDI" (at 144.145 94.615 0)
    (effects (font (size 2.54 2.54) (thickness 0.508) bold) (justify left bottom))
  )
  (text "Mount for debug \ninterface on USB-C PD" (at 89.535 109.22 0)
    (effects (font (size 0.9906 0.9906)) (justify left bottom))
  )
  (text "Logic level conversion" (at 262.89 17.78 0)
    (effects (font (size 2.54 2.54) (thickness 0.508) bold) (justify left bottom))
  )
  (text "EEPROM" (at 121.92 241.3 0)
    (effects (font (size 2.54 2.54) (thickness 0.508) bold) (justify left bottom))
  )
  (text "Decoupling and Filtering" (at 15.24 92.71 0)
    (effects (font (size 2.54 2.54) (thickness 0.508) bold) (justify left bottom))
  )
  (text "Optional debug USB" (at 13.97 17.78 0)
    (effects (font (size 2.54 2.54) (thickness 0.508) bold) (justify left bottom))
  )
  (text "Used as tri-state buffer" (at 300.355 172.72 0)
    (effects (font (size 1.27 1.27)) (justify left bottom))
  )
  (text "A2 -> B" (at 301.625 170.18 0)
    (effects (font (size 1.27 1.27)) (justify left bottom))
  )
  (text "Mount for debug \ninterface on USB-C debug" (at 109.855 109.22 0)
    (effects (font (size 0.9906 0.9906)) (justify left bottom))
  )
  (text "1 A <- B" (at 314.325 111.76 0)
    (effects (font (size 1.27 1.27)) (justify left bottom))
  )
  (text "Enables logic level conventer,\ndisables JTAG from FTDI when JTAG connector is used"
    (at 191.77 81.28 0)
    (effects (font (size 1.27 1.27)) (justify left bottom))
  )
  (text "2 A <- B" (at 314.325 114.3 0)
    (effects (font (size 1.27 1.27)) (justify left bottom))
  )
  (text "Logic level conversion enable" (at 189.23 17.78 0)
    (effects (font (size 2.54 2.54) (thickness 0.508) bold) (justify left bottom))
  )
  (text "Crystal" (at 81.28 141.605 0)
    (effects (font (size 2.54 2.54) (thickness 0.508) bold) (justify left bottom))
  )
  (text "A2 -> B" (at 301.625 205.74 0)
    (effects (font (size 1.27 1.27)) (justify left bottom))
  )
  (text "JTAG connector" (at 200.66 240.03 0)
    (effects (font (size 2.54 2.54) (thickness 0.508) bold) (justify left bottom))
  )
  (text "Supply" (at 78.74 17.78 0)
    (effects (font (size 2.54 2.54) (thickness 0.508) bold) (justify left bottom))
  )
  (text "1 A -> B" (at 314.325 73.025 0)
    (effects (font (size 1.27 1.27)) (justify left bottom))
  )
  (text "A1 <- B" (at 301.625 203.2 0)
    (effects (font (size 1.27 1.27)) (justify left bottom))
  )

  (label "EECLK" (at 172.72 168.91 0) (fields_autoplaced)
    (effects (font (size 1.27 1.27)) (justify left bottom))
  )
  (label "USB_1V2" (at 70.358 123.19 180) (fields_autoplaced)
    (effects (font (size 1.27 1.27)) (justify right bottom))
  )
  (label "USB_3V3" (at 24.384 153.67 0) (fields_autoplaced)
    (effects (font (size 1.27 1.27)) (justify left bottom))
  )
  (label "USB_3V3" (at 275.082 51.308 0) (fields_autoplaced)
    (effects (font (size 1.27 1.27)) (justify left bottom))
  )
  (label "VREGIN" (at 172.72 115.57 0) (fields_autoplaced)
    (effects (font (size 1.27 1.27)) (justify left bottom))
  )
  (label "EECS" (at 172.72 166.37 0) (fields_autoplaced)
    (effects (font (size 1.27 1.27)) (justify left bottom))
  )
  (label "~{LS_OE}" (at 254.508 41.91 180) (fields_autoplaced)
    (effects (font (size 1.27 1.27)) (justify right bottom))
  )
  (label "JTAG_VCCO_ON" (at 291.084 104.775 0) (fields_autoplaced)
    (effects (font (size 1.27 1.27)) (justify left bottom))
  )
  (label "USB_3V3" (at 262.255 184.785 0) (fields_autoplaced)
    (effects (font (size 1.27 1.27)) (justify left bottom))
  )
  (label "USB_3V3" (at 25.146 203.2 0) (fields_autoplaced)
    (effects (font (size 1.27 1.27)) (justify left bottom))
  )
  (label "~{LS_OE}" (at 299.085 89.535 0) (fields_autoplaced)
    (effects (font (size 1.27 1.27)) (justify left bottom))
  )
  (label "~{FTDI_LS_OE}" (at 251.46 128.27 180) (fields_autoplaced)
    (effects (font (size 1.27 1.27)) (justify right bottom))
  )
  (label "XIN" (at 95.885 154.94 0) (fields_autoplaced)
    (effects (font (size 1.27 1.27)) (justify left bottom))
  )
  (label "FTDI_TCK" (at 251.46 115.57 180) (fields_autoplaced)
    (effects (font (size 1.27 1.27)) (justify right bottom))
  )
  (label "USBC_CC1" (at 172.72 153.67 0) (fields_autoplaced)
    (effects (font (size 1.27 1.27)) (justify left bottom))
  )
  (label "USB_3V3" (at 62.865 100.965 180) (fields_autoplaced)
    (effects (font (size 1.27 1.27)) (justify right bottom))
  )
  (label "VCC_USB" (at 172.72 120.65 0) (fields_autoplaced)
    (effects (font (size 1.27 1.27)) (justify left bottom))
  )
  (label "USB_3V3" (at 268.605 149.225 0) (fields_autoplaced)
    (effects (font (size 1.27 1.27)) (justify left bottom))
  )
  (label "~{LS_OE}" (at 298.45 50.8 0) (fields_autoplaced)
    (effects (font (size 1.27 1.27)) (justify left bottom))
  )
  (label "USB_N" (at 108.585 121.92 0) (fields_autoplaced)
    (effects (font (size 1.27 1.27)) (justify left bottom))
  )
  (label "PD1_SVBUS" (at 182.245 53.975 180) (fields_autoplaced)
    (effects (font (size 1.27 1.27)) (justify right bottom))
  )
  (label "XIN" (at 172.72 177.8 0) (fields_autoplaced)
    (effects (font (size 1.27 1.27)) (justify left bottom))
  )
  (label "USB_P" (at 108.585 116.84 0) (fields_autoplaced)
    (effects (font (size 1.27 1.27)) (justify left bottom))
  )
  (label "USB_VBUS" (at 69.469 226.695 180) (fields_autoplaced)
    (effects (font (size 1.27 1.27)) (justify right bottom))
  )
  (label "USB_1V2" (at 172.72 127 0) (fields_autoplaced)
    (effects (font (size 1.27 1.27)) (justify left bottom))
  )
  (label "CONN_GND" (at 241.808 271.78 180) (fields_autoplaced)
    (effects (font (size 1.27 1.27)) (justify right bottom))
  )
  (label "FTDI_TDI" (at 298.45 66.04 0) (fields_autoplaced)
    (effects (font (size 1.27 1.27)) (justify left bottom))
  )
  (label "XOUT" (at 172.72 182.88 0) (fields_autoplaced)
    (effects (font (size 1.27 1.27)) (justify left bottom))
  )
  (label "USB_VBUS" (at 86.995 34.925 0) (fields_autoplaced)
    (effects (font (size 1.27 1.27)) (justify left bottom))
  )
  (label "FTDI_TDO" (at 291.338 99.695 0) (fields_autoplaced)
    (effects (font (size 1.27 1.27)) (justify left bottom))
  )
  (label "~{FTDI_PS_POR}" (at 251.46 130.81 180) (fields_autoplaced)
    (effects (font (size 1.27 1.27)) (justify right bottom))
  )
  (label "VCC_PD" (at 60.452 177.8 180) (fields_autoplaced)
    (effects (font (size 1.27 1.27)) (justify right bottom))
  )
  (label "XOUT" (at 123.825 154.94 180) (fields_autoplaced)
    (effects (font (size 1.27 1.27)) (justify right bottom))
  )
  (label "~{FTDI_PWREN}" (at 251.206 213.36 180) (fields_autoplaced)
    (effects (font (size 1.27 1.27)) (justify right bottom))
  )
  (label "~{FTDI_PWREN}" (at 284.48 162.56 0) (fields_autoplaced)
    (effects (font (size 1.27 1.27)) (justify left bottom))
  )
  (label "FTDI_TMS" (at 298.45 60.96 0) (fields_autoplaced)
    (effects (font (size 1.27 1.27)) (justify left bottom))
  )
  (label "EEDATA" (at 196.85 266.7 180) (fields_autoplaced)
    (effects (font (size 1.27 1.27)) (justify right bottom))
  )
  (label "USB_3V3" (at 196.85 251.46 180) (fields_autoplaced)
    (effects (font (size 1.27 1.27)) (justify right bottom))
  )
  (label "USB_3V3" (at 265.684 94.615 0) (fields_autoplaced)
    (effects (font (size 1.27 1.27)) (justify left bottom))
  )
  (label "FTDI_TMS" (at 251.46 123.19 180) (fields_autoplaced)
    (effects (font (size 1.27 1.27)) (justify right bottom))
  )
  (label "~{FTDI_PS_SRST}" (at 284.48 152.4 0) (fields_autoplaced)
    (effects (font (size 1.27 1.27)) (justify left bottom))
  )
  (label "USB_3V3" (at 299.085 86.995 0) (fields_autoplaced)
    (effects (font (size 1.27 1.27)) (justify left bottom))
  )
  (label "USB_3V3" (at 222.25 106.045 0) (fields_autoplaced)
    (effects (font (size 1.27 1.27)) (justify left bottom))
  )
  (label "VCC_PD" (at 172.72 123.19 0) (fields_autoplaced)
    (effects (font (size 1.27 1.27)) (justify left bottom))
  )
  (label "~{FTDI_PS_SRST}" (at 251.46 133.35 180) (fields_autoplaced)
    (effects (font (size 1.27 1.27)) (justify right bottom))
  )
  (label "FTDI_TCK" (at 298.45 63.5 0) (fields_autoplaced)
    (effects (font (size 1.27 1.27)) (justify left bottom))
  )
  (label "USB_3V3" (at 281.94 184.15 0) (fields_autoplaced)
    (effects (font (size 1.27 1.27)) (justify left bottom))
  )
  (label "FTDI_TDO" (at 251.46 120.65 180) (fields_autoplaced)
    (effects (font (size 1.27 1.27)) (justify right bottom))
  )
  (label "FTDI_UARTB_TXD" (at 281.94 190.5 0) (fields_autoplaced)
    (effects (font (size 1.27 1.27)) (justify left bottom))
  )
  (label "FTDI_UARTB_TXD" (at 251.46 137.16 180) (fields_autoplaced)
    (effects (font (size 1.27 1.27)) (justify right bottom))
  )
  (label "FTDI_EEPROM_WC" (at 294.894 228.6 0) (fields_autoplaced)
    (effects (font (size 1.27 1.27)) (justify left bottom))
  )
  (label "EECS" (at 196.85 261.62 180) (fields_autoplaced)
    (effects (font (size 1.27 1.27)) (justify right bottom))
  )
  (label "USB_VBUS" (at 83.82 57.15 0) (fields_autoplaced)
    (effects (font (size 1.27 1.27)) (justify left bottom))
  )
  (label "FTDI_UARTB_RXD" (at 251.46 139.7 180) (fields_autoplaced)
    (effects (font (size 1.27 1.27)) (justify right bottom))
  )
  (label "USB_P" (at 172.72 140.97 0) (fields_autoplaced)
    (effects (font (size 1.27 1.27)) (justify left bottom))
  )
  (label "USBB_N" (at 140.462 121.92 180) (fields_autoplaced)
    (effects (font (size 1.27 1.27)) (justify right bottom))
  )
  (label "EECLK" (at 196.85 264.16 180) (fields_autoplaced)
    (effects (font (size 1.27 1.27)) (justify right bottom))
  )
  (label "FTDI_UARTB_RXD" (at 281.94 187.96 0) (fields_autoplaced)
    (effects (font (size 1.27 1.27)) (justify left bottom))
  )
  (label "FTDI_EEPROM_WC" (at 251.46 182.88 180) (fields_autoplaced)
    (effects (font (size 1.27 1.27)) (justify right bottom))
  )
  (label "USB_3V3" (at 172.72 118.11 0) (fields_autoplaced)
    (effects (font (size 1.27 1.27)) (justify left bottom))
  )
  (label "USB_3V3" (at 281.94 195.58 0) (fields_autoplaced)
    (effects (font (size 1.27 1.27)) (justify left bottom))
  )
  (label "USB_3V3" (at 298.45 55.88 0) (fields_autoplaced)
    (effects (font (size 1.27 1.27)) (justify left bottom))
  )
  (label "USBC_CC2" (at 172.72 156.21 0) (fields_autoplaced)
    (effects (font (size 1.27 1.27)) (justify left bottom))
  )
  (label "USBB_P" (at 69.215 48.26 180) (fields_autoplaced)
    (effects (font (size 1.27 1.27)) (justify right bottom))
  )
  (label "USB_3V3" (at 284.48 148.59 0) (fields_autoplaced)
    (effects (font (size 1.27 1.27)) (justify left bottom))
  )
  (label "PD_3V3" (at 131.445 34.925 180) (fields_autoplaced)
    (effects (font (size 1.27 1.27)) (justify right bottom))
  )
  (label "JTAG_VCCO_ON" (at 251.46 125.73 180) (fields_autoplaced)
    (effects (font (size 1.27 1.27)) (justify right bottom))
  )
  (label "USBB_VBUS" (at 68.58 33.02 180) (fields_autoplaced)
    (effects (font (size 1.27 1.27)) (justify right bottom))
  )
  (label "USBB_P" (at 140.462 116.84 180) (fields_autoplaced)
    (effects (font (size 1.27 1.27)) (justify right bottom))
  )
  (label "CONN_GND" (at 204.978 49.53 0) (fields_autoplaced)
    (effects (font (size 1.27 1.27)) (justify left bottom))
  )
  (label "USB_3V3" (at 161.925 161.29 0) (fields_autoplaced)
    (effects (font (size 1.27 1.27)) (justify left bottom))
  )
  (label "USB_3V3" (at 284.48 157.48 0) (fields_autoplaced)
    (effects (font (size 1.27 1.27)) (justify left bottom))
  )
  (label "USB_3V3" (at 298.45 48.26 0) (fields_autoplaced)
    (effects (font (size 1.27 1.27)) (justify left bottom))
  )
  (label "EEDATA" (at 172.72 171.45 0) (fields_autoplaced)
    (effects (font (size 1.27 1.27)) (justify left bottom))
  )
  (label "USBB_VBUS" (at 21.463 230.759 0) (fields_autoplaced)
    (effects (font (size 1.27 1.27)) (justify left bottom))
  )
  (label "VCC_PD" (at 172.72 151.13 0) (fields_autoplaced)
    (effects (font (size 1.27 1.27)) (justify left bottom))
  )
  (label "USB_3V3" (at 132.08 57.15 180) (fields_autoplaced)
    (effects (font (size 1.27 1.27)) (justify right bottom))
  )
  (label "USB_N" (at 172.72 143.51 0) (fields_autoplaced)
    (effects (font (size 1.27 1.27)) (justify left bottom))
  )
  (label "VREGIN" (at 59.69 203.2 180) (fields_autoplaced)
    (effects (font (size 1.27 1.27)) (justify right bottom))
  )
  (label "USBB_N" (at 69.215 53.34 180) (fields_autoplaced)
    (effects (font (size 1.27 1.27)) (justify right bottom))
  )
  (label "~{FTDI_LS_OE}" (at 191.262 60.96 0) (fields_autoplaced)
    (effects (font (size 1.27 1.27)) (justify left bottom))
  )
  (label "PD1_SVBUS" (at 172.72 148.59 0) (fields_autoplaced)
    (effects (font (size 1.27 1.27)) (justify left bottom))
  )
  (label "USB_3V3" (at 208.026 37.465 0) (fields_autoplaced)
    (effects (font (size 1.27 1.27)) (justify left bottom))
  )
  (label "PD_3V3" (at 24.892 177.8 0) (fields_autoplaced)
    (effects (font (size 1.27 1.27)) (justify left bottom))
  )
  (label "USB_3V3" (at 374.65 137.16 180) (fields_autoplaced)
    (effects (font (size 1.27 1.27)) (justify right bottom))
  )
  (label "~{FTDI_PS_POR}" (at 284.48 154.94 0) (fields_autoplaced)
    (effects (font (size 1.27 1.27)) (justify left bottom))
  )
  (label "FTDI_TDI" (at 251.46 118.11 180) (fields_autoplaced)
    (effects (font (size 1.27 1.27)) (justify right bottom))
  )
  (label "USB_3V3" (at 224.282 30.734 0) (fields_autoplaced)
    (effects (font (size 1.27 1.27)) (justify left bottom))
  )
  (label "USB_3V3" (at 123.063 261.62 0) (fields_autoplaced)
    (effects (font (size 1.27 1.27)) (justify left bottom))
  )
  (label "VCC_USB" (at 60.706 153.67 180) (fields_autoplaced)
    (effects (font (size 1.27 1.27)) (justify right bottom))
  )

  (global_label "PS_1V8" (shape input) (at 349.885 185.42 180) (fields_autoplaced)
    (effects (font (size 1.27 1.27)) (justify right))
    (property "Intersheetrefs" "${INTERSHEET_REFS}" (at 340.606 185.4994 0)
      (effects (font (size 1.27 1.27)) (justify right) hide)
    )
  )
  (global_label "PS_1V8" (shape input) (at 243.205 243.84 0) (fields_autoplaced)
    (effects (font (size 1.27 1.27)) (justify left))
    (property "Intersheetrefs" "${INTERSHEET_REFS}" (at 252.484 243.7606 0)
      (effects (font (size 1.27 1.27)) (justify left) hide)
    )
  )
  (global_label "PS_1V8" (shape input) (at 336.55 104.775 0) (fields_autoplaced)
    (effects (font (size 1.27 1.27)) (justify left))
    (property "Intersheetrefs" "${INTERSHEET_REFS}" (at 345.829 104.6956 0)
      (effects (font (size 1.27 1.27)) (justify left) hide)
    )
  )
  (global_label "SH_DOWN" (shape input) (at 36.195 76.835 180) (fields_autoplaced)
    (effects (font (size 1.27 1.27)) (justify right))
    (property "Intersheetrefs" "${INTERSHEET_REFS}" (at 24.9808 76.7556 0)
      (effects (font (size 1.27 1.27)) (justify right) hide)
    )
  )
  (global_label "PS_1V8" (shape input) (at 358.14 93.98 180) (fields_autoplaced)
    (effects (font (size 1.27 1.27)) (justify right))
    (property "Intersheetrefs" "${INTERSHEET_REFS}" (at 348.861 94.0594 0)
      (effects (font (size 1.27 1.27)) (justify right) hide)
    )
  )
  (global_label "PS_1V8" (shape input) (at 325.247 184.15 0) (fields_autoplaced)
    (effects (font (size 1.27 1.27)) (justify left))
    (property "Intersheetrefs" "${INTERSHEET_REFS}" (at 334.526 184.0706 0)
      (effects (font (size 1.27 1.27)) (justify left) hide)
    )
  )
  (global_label "PS_1V8" (shape input) (at 338.455 48.26 0) (fields_autoplaced)
    (effects (font (size 1.27 1.27)) (justify left))
    (property "Intersheetrefs" "${INTERSHEET_REFS}" (at 347.734 48.1806 0)
      (effects (font (size 1.27 1.27)) (justify left) hide)
    )
  )
  (global_label "PS_1V8" (shape input) (at 365.125 52.07 180) (fields_autoplaced)
    (effects (font (size 1.27 1.27)) (justify right))
    (property "Intersheetrefs" "${INTERSHEET_REFS}" (at 355.846 52.1494 0)
      (effects (font (size 1.27 1.27)) (justify right) hide)
    )
  )
  (global_label "PS_1V8" (shape input) (at 336.55 86.995 0) (fields_autoplaced)
    (effects (font (size 1.27 1.27)) (justify left))
    (property "Intersheetrefs" "${INTERSHEET_REFS}" (at 345.829 86.9156 0)
      (effects (font (size 1.27 1.27)) (justify left) hide)
    )
  )

  (hierarchical_label "JTAG_TDI_C2M" (shape input) (at 269.875 266.7 0) (fields_autoplaced)
    (effects (font (size 1.27 1.27)) (justify left))
  )
  (hierarchical_label "USBC_CC[1..2]" (shape input) (at 165.1 148.59 180) (fields_autoplaced)
    (effects (font (size 1.27 1.27)) (justify right))
  )
  (hierarchical_label "JTAG_TMS_C2M" (shape input) (at 332.74 60.96 0) (fields_autoplaced)
    (effects (font (size 1.27 1.27)) (justify left))
  )
  (hierarchical_label "USBC_P" (shape input) (at 87.63 116.84 180) (fields_autoplaced)
    (effects (font (size 1.27 1.27)) (justify right))
  )
  (hierarchical_label "JTAG_TDO_M2C" (shape input) (at 336.55 99.695 0) (fields_autoplaced)
    (effects (font (size 1.27 1.27)) (justify left))
  )
  (hierarchical_label "JTAG_TDI_C2M" (shape input) (at 332.74 66.04 0) (fields_autoplaced)
    (effects (font (size 1.27 1.27)) (justify left))
  )
  (hierarchical_label "~{EEPROM_WC}" (shape input) (at 327.66 220.98 0) (fields_autoplaced)
    (effects (font (size 1.27 1.27)) (justify left))
  )
  (hierarchical_label "USBC_N" (shape input) (at 87.63 121.92 180) (fields_autoplaced)
    (effects (font (size 1.27 1.27)) (justify right))
  )
  (hierarchical_label "PD_EN" (shape input) (at 228.6 207.01 0) (fields_autoplaced)
    (effects (font (size 1.27 1.27)) (justify left))
  )
  (hierarchical_label "JTAG_TCK_C2M" (shape input) (at 332.74 63.5 0) (fields_autoplaced)
    (effects (font (size 1.27 1.27)) (justify left))
  )
  (hierarchical_label "MIO36" (shape input) (at 326.39 187.96 0) (fields_autoplaced)
    (effects (font (size 1.27 1.27)) (justify left))
  )
  (hierarchical_label "USBC_VBUS" (shape input) (at 157.48 43.815 180) (fields_autoplaced)
    (effects (font (size 1.27 1.27)) (justify right))
  )
  (hierarchical_label "USBC_VBUS" (shape input) (at 33.655 222.377 180) (fields_autoplaced)
    (effects (font (size 1.27 1.27)) (justify right))
  )
  (hierarchical_label "MIO37" (shape input) (at 326.39 190.5 0) (fields_autoplaced)
    (effects (font (size 1.27 1.27)) (justify left))
  )
  (hierarchical_label "JTAG_TCK_C2M" (shape input) (at 269.875 261.62 0) (fields_autoplaced)
    (effects (font (size 1.27 1.27)) (justify left))
  )
  (hierarchical_label "JTAG_TDO_M2C" (shape input) (at 269.875 264.16 0) (fields_autoplaced)
    (effects (font (size 1.27 1.27)) (justify left))
  )
  (hierarchical_label "JTAG_TMS_C2M" (shape input) (at 269.875 259.08 0) (fields_autoplaced)
    (effects (font (size 1.27 1.27)) (justify left))
  )
  (hierarchical_label "~{PS_POR}" (shape input) (at 381 158.75 0) (fields_autoplaced)
    (effects (font (size 1.27 1.27)) (justify left))
  )
  (hierarchical_label "~{PS_SRST_C2M}" (shape input) (at 381 152.4 0) (fields_autoplaced)
    (effects (font (size 1.27 1.27)) (justify left))
  )
  (hierarchical_label "~{PS_SRST_C2M}" (shape input) (at 215.9 271.78 180) (fields_autoplaced)
    (effects (font (size 1.27 1.27)) (justify right))
  )

  (symbol (lib_id "kria-k26-devboard:R_10k_0402") (at 217.17 40.64 270) (unit 1)
    (in_bom yes) (on_board yes) (dnp no) (fields_autoplaced)
    (property "Reference" "R111" (at 214.63 41.91 90)
      (effects (font (size 1.524 1.524)) (justify right))
    )
    (property "Value" "R_10k_0402" (at 213.36 40.64 0)
      (effects (font (size 1.27 1.27) (thickness 0.15)) (justify left bottom) hide)
    )
    (property "Footprint" "kria-k26-devboard-footprints:R_0402_1005Metric" (at 222.25 45.72 0)
      (effects (font (size 1.27 1.27) (thickness 0.15)) (justify left bottom) hide)
    )
    (property "Datasheet" "https://www.bourns.com/docs/product-datasheets/cr.pdf" (at 217.17 40.64 0)
      (effects (font (size 1.27 1.27) (thickness 0.15)) (justify left bottom) hide)
    )
    (property "Manufacturer" "Bourns" (at 227.33 45.72 0)
      (effects (font (size 1.27 1.27) (thickness 0.15)) (justify left bottom) hide)
    )
    (property "MPN" "CR0402-FX-1002GLF" (at 224.79 45.72 0)
      (effects (font (size 1.27 1.27) (thickness 0.15)) (justify left bottom) hide)
    )
    (property "Val" "10k" (at 214.63 45.0849 90)
      (effects (font (size 1.27 1.27) (thickness 0.15)) (justify right))
    )
    (property "License" "Apache-2.0" (at 191.77 60.96 0)
      (effects (font (size 1.27 1.27) (thickness 0.15)) (justify left bottom) hide)
    )
    (property "Author" "Antmicro" (at 189.23 60.96 0)
      (effects (font (size 1.27 1.27) (thickness 0.15)) (justify left bottom) hide)
    )
    (property "Tolerance" "1%" (at 207.01 60.96 0)
      (effects (font (size 1.27 1.27)) (justify left bottom) hide)
    )
    (pin "1")
    (pin "2")
    (instances
      (project "kria-k26-devboard"
        (path ""
          (reference "R111") (unit 1)
        )
      )
    )
  )

  (symbol (lib_id "kria-k26-devboard:R_10k_0402") (at 233.68 33.655 270) (unit 1)
    (in_bom yes) (on_board yes) (dnp no) (fields_autoplaced)
    (property "Reference" "R112" (at 231.14 34.925 90)
      (effects (font (size 1.524 1.524)) (justify right))
    )
    (property "Value" "R_10k_0402" (at 229.87 33.655 0)
      (effects (font (size 1.27 1.27) (thickness 0.15)) (justify left bottom) hide)
    )
    (property "Footprint" "kria-k26-devboard-footprints:R_0402_1005Metric" (at 238.76 38.735 0)
      (effects (font (size 1.27 1.27) (thickness 0.15)) (justify left bottom) hide)
    )
    (property "Datasheet" "https://www.bourns.com/docs/product-datasheets/cr.pdf" (at 233.68 33.655 0)
      (effects (font (size 1.27 1.27) (thickness 0.15)) (justify left bottom) hide)
    )
    (property "Manufacturer" "Bourns" (at 243.84 38.735 0)
      (effects (font (size 1.27 1.27) (thickness 0.15)) (justify left bottom) hide)
    )
    (property "MPN" "CR0402-FX-1002GLF" (at 241.3 38.735 0)
      (effects (font (size 1.27 1.27) (thickness 0.15)) (justify left bottom) hide)
    )
    (property "Val" "10k" (at 231.14 38.0999 90)
      (effects (font (size 1.27 1.27) (thickness 0.15)) (justify right))
    )
    (property "License" "Apache-2.0" (at 208.28 53.975 0)
      (effects (font (size 1.27 1.27) (thickness 0.15)) (justify left bottom) hide)
    )
    (property "Author" "Antmicro" (at 205.74 53.975 0)
      (effects (font (size 1.27 1.27) (thickness 0.15)) (justify left bottom) hide)
    )
    (property "Tolerance" "1%" (at 223.52 53.975 0)
      (effects (font (size 1.27 1.27)) (justify left bottom) hide)
    )
    (pin "1")
    (pin "2")
    (instances
      (project "kria-k26-devboard"
        (path ""
          (reference "R112") (unit 1)
        )
      )
    )
  )

  (symbol (lib_id "kria-k26-devboard:GND") (at 217.17 66.04 0) (unit 1)
    (in_bom yes) (on_board yes) (dnp no) (fields_autoplaced)
    (property "Reference" "#PWR0339" (at 217.17 72.39 0)
      (effects (font (size 1.27 1.27)) hide)
    )
    (property "Value" "GND" (at 217.17 70.866 0)
      (effects (font (size 1.27 1.27)))
    )
    (property "Footprint" "" (at 226.06 73.66 0)
      (effects (font (size 1.27 1.27) (thickness 0.15)) (justify left bottom) hide)
    )
    (property "Datasheet" "" (at 226.06 78.74 0)
      (effects (font (size 1.27 1.27) (thickness 0.15)) (justify left bottom) hide)
    )
    (property "Author" "Antmicro" (at 226.06 73.66 0)
      (effects (font (size 1.27 1.27) (thickness 0.15)) (justify left bottom) hide)
    )
    (property "License" "Apache-2.0" (at 226.06 76.2 0)
      (effects (font (size 1.27 1.27) (thickness 0.15)) (justify left bottom) hide)
    )
    (pin "1")
    (instances
      (project "kria-k26-devboard"
        (path ""
          (reference "#PWR0339") (unit 1)
        )
      )
    )
  )

  (symbol (lib_id "kria-k26-devboard:GND") (at 233.68 54.61 0) (unit 1)
    (in_bom yes) (on_board yes) (dnp no) (fields_autoplaced)
    (property "Reference" "#PWR0341" (at 233.68 60.96 0)
      (effects (font (size 1.27 1.27)) hide)
    )
    (property "Value" "GND" (at 233.68 59.69 0)
      (effects (font (size 1.27 1.27)))
    )
    (property "Footprint" "" (at 242.57 62.23 0)
      (effects (font (size 1.27 1.27) (thickness 0.15)) (justify left bottom) hide)
    )
    (property "Datasheet" "" (at 242.57 67.31 0)
      (effects (font (size 1.27 1.27) (thickness 0.15)) (justify left bottom) hide)
    )
    (property "Author" "Antmicro" (at 242.57 62.23 0)
      (effects (font (size 1.27 1.27) (thickness 0.15)) (justify left bottom) hide)
    )
    (property "License" "Apache-2.0" (at 242.57 64.77 0)
      (effects (font (size 1.27 1.27) (thickness 0.15)) (justify left bottom) hide)
    )
    (pin "1")
    (instances
      (project "kria-k26-devboard"
        (path ""
          (reference "#PWR0341") (unit 1)
        )
      )
    )
  )

  (symbol (lib_id "kria-k26-devboard:R_10k_0402") (at 231.14 107.95 270) (unit 1)
    (in_bom yes) (on_board yes) (dnp no) (fields_autoplaced)
    (property "Reference" "R109" (at 233.68 109.22 90)
      (effects (font (size 1.524 1.524)) (justify left))
    )
    (property "Value" "R_10k_0402" (at 227.33 107.95 0)
      (effects (font (size 1.27 1.27) (thickness 0.15)) (justify left bottom) hide)
    )
    (property "Footprint" "kria-k26-devboard-footprints:R_0402_1005Metric" (at 236.22 113.03 0)
      (effects (font (size 1.27 1.27) (thickness 0.15)) (justify left bottom) hide)
    )
    (property "Datasheet" "https://www.bourns.com/docs/product-datasheets/cr.pdf" (at 231.14 107.95 0)
      (effects (font (size 1.27 1.27) (thickness 0.15)) (justify left bottom) hide)
    )
    (property "Manufacturer" "Bourns" (at 241.3 113.03 0)
      (effects (font (size 1.27 1.27) (thickness 0.15)) (justify left bottom) hide)
    )
    (property "MPN" "CR0402-FX-1002GLF" (at 238.76 113.03 0)
      (effects (font (size 1.27 1.27) (thickness 0.15)) (justify left bottom) hide)
    )
    (property "Val" "10k" (at 233.68 112.3949 90)
      (effects (font (size 1.27 1.27) (thickness 0.15)) (justify left))
    )
    (property "License" "Apache-2.0" (at 205.74 128.27 0)
      (effects (font (size 1.27 1.27) (thickness 0.15)) (justify left bottom) hide)
    )
    (property "Author" "Antmicro" (at 203.2 128.27 0)
      (effects (font (size 1.27 1.27) (thickness 0.15)) (justify left bottom) hide)
    )
    (property "Tolerance" "1%" (at 220.98 128.27 0)
      (effects (font (size 1.27 1.27)) (justify left bottom) hide)
    )
    (pin "1")
    (pin "2")
    (instances
      (project "kria-k26-devboard"
        (path ""
          (reference "R109") (unit 1)
        )
      )
    )
  )

  (symbol (lib_id "kria-k26-devboard:GND") (at 307.34 71.12 0) (unit 1)
    (in_bom yes) (on_board yes) (dnp no) (fields_autoplaced)
    (property "Reference" "#PWR0350" (at 307.34 77.47 0)
      (effects (font (size 1.27 1.27)) hide)
    )
    (property "Value" "GND" (at 307.34 76.2 0)
      (effects (font (size 1.27 1.27)))
    )
    (property "Footprint" "" (at 316.23 78.74 0)
      (effects (font (size 1.27 1.27) (thickness 0.15)) (justify left bottom) hide)
    )
    (property "Datasheet" "" (at 316.23 83.82 0)
      (effects (font (size 1.27 1.27) (thickness 0.15)) (justify left bottom) hide)
    )
    (property "Author" "Antmicro" (at 316.23 78.74 0)
      (effects (font (size 1.27 1.27) (thickness 0.15)) (justify left bottom) hide)
    )
    (property "License" "Apache-2.0" (at 316.23 81.28 0)
      (effects (font (size 1.27 1.27) (thickness 0.15)) (justify left bottom) hide)
    )
    (pin "1")
    (instances
      (project "kria-k26-devboard"
        (path ""
          (reference "#PWR0350") (unit 1)
        )
      )
    )
  )

  (symbol (lib_id "kria-k26-devboard:GND") (at 330.2 52.07 0) (unit 1)
    (in_bom yes) (on_board yes) (dnp no) (fields_autoplaced)
    (property "Reference" "#PWR0352" (at 330.2 58.42 0)
      (effects (font (size 1.27 1.27)) hide)
    )
    (property "Value" "GND" (at 332.74 53.3399 0)
      (effects (font (size 1.27 1.27)) (justify left))
    )
    (property "Footprint" "" (at 339.09 59.69 0)
      (effects (font (size 1.27 1.27) (thickness 0.15)) (justify left bottom) hide)
    )
    (property "Datasheet" "" (at 339.09 64.77 0)
      (effects (font (size 1.27 1.27) (thickness 0.15)) (justify left bottom) hide)
    )
    (property "Author" "Antmicro" (at 339.09 59.69 0)
      (effects (font (size 1.27 1.27) (thickness 0.15)) (justify left bottom) hide)
    )
    (property "License" "Apache-2.0" (at 339.09 62.23 0)
      (effects (font (size 1.27 1.27) (thickness 0.15)) (justify left bottom) hide)
    )
    (pin "1")
    (instances
      (project "kria-k26-devboard"
        (path ""
          (reference "#PWR0352") (unit 1)
        )
      )
    )
  )

  (symbol (lib_id "kria-k26-devboard:GND") (at 306.705 111.76 0) (unit 1)
    (in_bom yes) (on_board yes) (dnp no) (fields_autoplaced)
    (property "Reference" "#PWR0351" (at 306.705 118.11 0)
      (effects (font (size 1.27 1.27)) hide)
    )
    (property "Value" "GND" (at 306.705 116.205 0)
      (effects (font (size 1.27 1.27)))
    )
    (property "Footprint" "" (at 315.595 119.38 0)
      (effects (font (size 1.27 1.27) (thickness 0.15)) (justify left bottom) hide)
    )
    (property "Datasheet" "" (at 315.595 124.46 0)
      (effects (font (size 1.27 1.27) (thickness 0.15)) (justify left bottom) hide)
    )
    (property "Author" "Antmicro" (at 315.595 119.38 0)
      (effects (font (size 1.27 1.27) (thickness 0.15)) (justify left bottom) hide)
    )
    (property "License" "Apache-2.0" (at 315.595 121.92 0)
      (effects (font (size 1.27 1.27) (thickness 0.15)) (justify left bottom) hide)
    )
    (pin "1")
    (instances
      (project "kria-k26-devboard"
        (path ""
          (reference "#PWR0351") (unit 1)
        )
      )
    )
  )

  (symbol (lib_id "kria-k26-devboard:GND") (at 334.01 109.855 0) (unit 1)
    (in_bom yes) (on_board yes) (dnp no) (fields_autoplaced)
    (property "Reference" "#PWR0355" (at 334.01 116.205 0)
      (effects (font (size 1.27 1.27)) hide)
    )
    (property "Value" "GND" (at 334.01 114.935 0)
      (effects (font (size 1.27 1.27)))
    )
    (property "Footprint" "" (at 342.9 117.475 0)
      (effects (font (size 1.27 1.27) (thickness 0.15)) (justify left bottom) hide)
    )
    (property "Datasheet" "" (at 342.9 122.555 0)
      (effects (font (size 1.27 1.27) (thickness 0.15)) (justify left bottom) hide)
    )
    (property "Author" "Antmicro" (at 342.9 117.475 0)
      (effects (font (size 1.27 1.27) (thickness 0.15)) (justify left bottom) hide)
    )
    (property "License" "Apache-2.0" (at 342.9 120.015 0)
      (effects (font (size 1.27 1.27) (thickness 0.15)) (justify left bottom) hide)
    )
    (pin "1")
    (instances
      (project "kria-k26-devboard"
        (path ""
          (reference "#PWR0355") (unit 1)
        )
      )
    )
  )

  (symbol (lib_id "kria-k26-devboard:GND") (at 330.2 90.805 0) (unit 1)
    (in_bom yes) (on_board yes) (dnp no) (fields_autoplaced)
    (property "Reference" "#PWR0353" (at 330.2 97.155 0)
      (effects (font (size 1.27 1.27)) hide)
    )
    (property "Value" "GND" (at 332.74 92.0749 0)
      (effects (font (size 1.27 1.27)) (justify left))
    )
    (property "Footprint" "" (at 339.09 98.425 0)
      (effects (font (size 1.27 1.27) (thickness 0.15)) (justify left bottom) hide)
    )
    (property "Datasheet" "" (at 339.09 103.505 0)
      (effects (font (size 1.27 1.27) (thickness 0.15)) (justify left bottom) hide)
    )
    (property "Author" "Antmicro" (at 339.09 98.425 0)
      (effects (font (size 1.27 1.27) (thickness 0.15)) (justify left bottom) hide)
    )
    (property "License" "Apache-2.0" (at 339.09 100.965 0)
      (effects (font (size 1.27 1.27) (thickness 0.15)) (justify left bottom) hide)
    )
    (pin "1")
    (instances
      (project "kria-k26-devboard"
        (path ""
          (reference "#PWR0353") (unit 1)
        )
      )
    )
  )

  (symbol (lib_id "kria-k26-devboard:C_100n_0402") (at 367.03 53.975 270) (unit 1)
    (in_bom yes) (on_board yes) (dnp no) (fields_autoplaced)
    (property "Reference" "C168" (at 369.57 55.2513 90)
      (effects (font (size 1.524 1.524)) (justify left))
    )
    (property "Value" "C_100n_0402" (at 363.22 53.975 0)
      (effects (font (size 1.27 1.27) (thickness 0.15)) (justify left bottom) hide)
    )
    (property "Footprint" "kria-k26-devboard-footprints:C_0402_1005Metric" (at 372.11 59.055 0)
      (effects (font (size 1.27 1.27) (thickness 0.15)) (justify left bottom) hide)
    )
    (property "Datasheet" "https://search.murata.co.jp/Ceramy/image/img/A01X/G101/ENG/GRM155R61H104KE14-01.pdf" (at 367.03 53.975 0)
      (effects (font (size 1.27 1.27) (thickness 0.15)) (justify left bottom) hide)
    )
    (property "Manufacturer" "Murata" (at 377.19 59.055 0)
      (effects (font (size 1.27 1.27) (thickness 0.15)) (justify left bottom) hide)
    )
    (property "MPN" "GRM155R61H104KE14D" (at 374.65 59.055 0)
      (effects (font (size 1.27 1.27) (thickness 0.15)) (justify left bottom) hide)
    )
    (property "Val" "100n" (at 369.57 58.4262 90)
      (effects (font (size 1.27 1.27) (thickness 0.15)) (justify left))
    )
    (property "License" "Apache-2.0" (at 344.17 74.295 0)
      (effects (font (size 1.27 1.27) (thickness 0.15)) (justify left bottom) hide)
    )
    (property "Author" "Antmicro" (at 341.63 74.295 0)
      (effects (font (size 1.27 1.27) (thickness 0.15)) (justify left bottom) hide)
    )
    (property "Voltage" "50V" (at 339.09 74.295 0)
      (effects (font (size 1.27 1.27)) (justify left bottom) hide)
    )
    (property "Dielectric" "X5R" (at 336.55 74.295 0)
      (effects (font (size 1.27 1.27)) (justify left bottom) hide)
    )
    (pin "1")
    (pin "2")
    (instances
      (project "kria-k26-devboard"
        (path ""
          (reference "C168") (unit 1)
        )
      )
    )
  )

  (symbol (lib_id "kria-k26-devboard:GND") (at 367.03 59.055 0) (unit 1)
    (in_bom yes) (on_board yes) (dnp no) (fields_autoplaced)
    (property "Reference" "#PWR0359" (at 367.03 65.405 0)
      (effects (font (size 1.27 1.27)) hide)
    )
    (property "Value" "GND" (at 367.03 64.643 0)
      (effects (font (size 1.27 1.27)))
    )
    (property "Footprint" "" (at 375.92 66.675 0)
      (effects (font (size 1.27 1.27) (thickness 0.15)) (justify left bottom) hide)
    )
    (property "Datasheet" "" (at 375.92 71.755 0)
      (effects (font (size 1.27 1.27) (thickness 0.15)) (justify left bottom) hide)
    )
    (property "Author" "Antmicro" (at 375.92 66.675 0)
      (effects (font (size 1.27 1.27) (thickness 0.15)) (justify left bottom) hide)
    )
    (property "License" "Apache-2.0" (at 375.92 69.215 0)
      (effects (font (size 1.27 1.27) (thickness 0.15)) (justify left bottom) hide)
    )
    (pin "1")
    (instances
      (project "kria-k26-devboard"
        (path ""
          (reference "#PWR0359") (unit 1)
        )
      )
    )
  )

  (symbol (lib_id "kria-k26-devboard:C_100n_0402") (at 284.48 52.705 270) (unit 1)
    (in_bom yes) (on_board yes) (dnp no) (fields_autoplaced)
    (property "Reference" "C162" (at 287.02 53.9813 90)
      (effects (font (size 1.524 1.524)) (justify left))
    )
    (property "Value" "C_100n_0402" (at 280.67 52.705 0)
      (effects (font (size 1.27 1.27) (thickness 0.15)) (justify left bottom) hide)
    )
    (property "Footprint" "kria-k26-devboard-footprints:C_0402_1005Metric" (at 289.56 57.785 0)
      (effects (font (size 1.27 1.27) (thickness 0.15)) (justify left bottom) hide)
    )
    (property "Datasheet" "https://search.murata.co.jp/Ceramy/image/img/A01X/G101/ENG/GRM155R61H104KE14-01.pdf" (at 284.48 52.705 0)
      (effects (font (size 1.27 1.27) (thickness 0.15)) (justify left bottom) hide)
    )
    (property "Manufacturer" "Murata" (at 294.64 57.785 0)
      (effects (font (size 1.27 1.27) (thickness 0.15)) (justify left bottom) hide)
    )
    (property "MPN" "GRM155R61H104KE14D" (at 292.1 57.785 0)
      (effects (font (size 1.27 1.27) (thickness 0.15)) (justify left bottom) hide)
    )
    (property "Val" "100n" (at 287.02 57.1562 90)
      (effects (font (size 1.27 1.27) (thickness 0.15)) (justify left))
    )
    (property "License" "Apache-2.0" (at 261.62 73.025 0)
      (effects (font (size 1.27 1.27) (thickness 0.15)) (justify left bottom) hide)
    )
    (property "Author" "Antmicro" (at 259.08 73.025 0)
      (effects (font (size 1.27 1.27) (thickness 0.15)) (justify left bottom) hide)
    )
    (property "Voltage" "50V" (at 256.54 73.025 0)
      (effects (font (size 1.27 1.27)) (justify left bottom) hide)
    )
    (property "Dielectric" "X5R" (at 254 73.025 0)
      (effects (font (size 1.27 1.27)) (justify left bottom) hide)
    )
    (pin "1")
    (pin "2")
    (instances
      (project "kria-k26-devboard"
        (path ""
          (reference "C162") (unit 1)
        )
      )
    )
  )

  (symbol (lib_id "kria-k26-devboard:GND") (at 284.48 57.785 0) (unit 1)
    (in_bom yes) (on_board yes) (dnp no) (fields_autoplaced)
    (property "Reference" "#PWR0344" (at 284.48 64.135 0)
      (effects (font (size 1.27 1.27)) hide)
    )
    (property "Value" "GND" (at 284.48 63.119 0)
      (effects (font (size 1.27 1.27)))
    )
    (property "Footprint" "" (at 293.37 65.405 0)
      (effects (font (size 1.27 1.27) (thickness 0.15)) (justify left bottom) hide)
    )
    (property "Datasheet" "" (at 293.37 70.485 0)
      (effects (font (size 1.27 1.27) (thickness 0.15)) (justify left bottom) hide)
    )
    (property "Author" "Antmicro" (at 293.37 65.405 0)
      (effects (font (size 1.27 1.27) (thickness 0.15)) (justify left bottom) hide)
    )
    (property "License" "Apache-2.0" (at 293.37 67.945 0)
      (effects (font (size 1.27 1.27) (thickness 0.15)) (justify left bottom) hide)
    )
    (pin "1")
    (instances
      (project "kria-k26-devboard"
        (path ""
          (reference "#PWR0344") (unit 1)
        )
      )
    )
  )

  (symbol (lib_id "kria-k26-devboard:C_100n_0402") (at 360.045 95.885 270) (unit 1)
    (in_bom yes) (on_board yes) (dnp no) (fields_autoplaced)
    (property "Reference" "C169" (at 363.22 97.1613 90)
      (effects (font (size 1.524 1.524)) (justify left))
    )
    (property "Value" "C_100n_0402" (at 356.235 95.885 0)
      (effects (font (size 1.27 1.27) (thickness 0.15)) (justify left bottom) hide)
    )
    (property "Footprint" "kria-k26-devboard-footprints:C_0402_1005Metric" (at 365.125 100.965 0)
      (effects (font (size 1.27 1.27) (thickness 0.15)) (justify left bottom) hide)
    )
    (property "Datasheet" "https://search.murata.co.jp/Ceramy/image/img/A01X/G101/ENG/GRM155R61H104KE14-01.pdf" (at 360.045 95.885 0)
      (effects (font (size 1.27 1.27) (thickness 0.15)) (justify left bottom) hide)
    )
    (property "Manufacturer" "Murata" (at 370.205 100.965 0)
      (effects (font (size 1.27 1.27) (thickness 0.15)) (justify left bottom) hide)
    )
    (property "MPN" "GRM155R61H104KE14D" (at 367.665 100.965 0)
      (effects (font (size 1.27 1.27) (thickness 0.15)) (justify left bottom) hide)
    )
    (property "Val" "100n" (at 363.22 100.3362 90)
      (effects (font (size 1.27 1.27) (thickness 0.15)) (justify left))
    )
    (property "License" "Apache-2.0" (at 337.185 116.205 0)
      (effects (font (size 1.27 1.27) (thickness 0.15)) (justify left bottom) hide)
    )
    (property "Author" "Antmicro" (at 334.645 116.205 0)
      (effects (font (size 1.27 1.27) (thickness 0.15)) (justify left bottom) hide)
    )
    (property "Voltage" "50V" (at 332.105 116.205 0)
      (effects (font (size 1.27 1.27)) (justify left bottom) hide)
    )
    (property "Dielectric" "X5R" (at 329.565 116.205 0)
      (effects (font (size 1.27 1.27)) (justify left bottom) hide)
    )
    (pin "1")
    (pin "2")
    (instances
      (project "kria-k26-devboard"
        (path ""
          (reference "C169") (unit 1)
        )
      )
    )
  )

  (symbol (lib_id "kria-k26-devboard:GND") (at 360.045 100.965 0) (unit 1)
    (in_bom yes) (on_board yes) (dnp no) (fields_autoplaced)
    (property "Reference" "#PWR0360" (at 360.045 107.315 0)
      (effects (font (size 1.27 1.27)) hide)
    )
    (property "Value" "GND" (at 360.045 105.537 0)
      (effects (font (size 1.27 1.27)))
    )
    (property "Footprint" "" (at 368.935 108.585 0)
      (effects (font (size 1.27 1.27) (thickness 0.15)) (justify left bottom) hide)
    )
    (property "Datasheet" "" (at 368.935 113.665 0)
      (effects (font (size 1.27 1.27) (thickness 0.15)) (justify left bottom) hide)
    )
    (property "Author" "Antmicro" (at 368.935 108.585 0)
      (effects (font (size 1.27 1.27) (thickness 0.15)) (justify left bottom) hide)
    )
    (property "License" "Apache-2.0" (at 368.935 111.125 0)
      (effects (font (size 1.27 1.27) (thickness 0.15)) (justify left bottom) hide)
    )
    (pin "1")
    (instances
      (project "kria-k26-devboard"
        (path ""
          (reference "#PWR0360") (unit 1)
        )
      )
    )
  )

  (symbol (lib_id "kria-k26-devboard:C_100n_0402") (at 274.32 96.52 270) (unit 1)
    (in_bom yes) (on_board yes) (dnp no) (fields_autoplaced)
    (property "Reference" "C163" (at 276.86 97.7963 90)
      (effects (font (size 1.524 1.524)) (justify left))
    )
    (property "Value" "C_100n_0402" (at 270.51 96.52 0)
      (effects (font (size 1.27 1.27) (thickness 0.15)) (justify left bottom) hide)
    )
    (property "Footprint" "kria-k26-devboard-footprints:C_0402_1005Metric" (at 279.4 101.6 0)
      (effects (font (size 1.27 1.27) (thickness 0.15)) (justify left bottom) hide)
    )
    (property "Datasheet" "https://search.murata.co.jp/Ceramy/image/img/A01X/G101/ENG/GRM155R61H104KE14-01.pdf" (at 274.32 96.52 0)
      (effects (font (size 1.27 1.27) (thickness 0.15)) (justify left bottom) hide)
    )
    (property "Manufacturer" "Murata" (at 284.48 101.6 0)
      (effects (font (size 1.27 1.27) (thickness 0.15)) (justify left bottom) hide)
    )
    (property "MPN" "GRM155R61H104KE14D" (at 281.94 101.6 0)
      (effects (font (size 1.27 1.27) (thickness 0.15)) (justify left bottom) hide)
    )
    (property "Val" "100n" (at 276.86 100.9712 90)
      (effects (font (size 1.27 1.27) (thickness 0.15)) (justify left))
    )
    (property "License" "Apache-2.0" (at 251.46 116.84 0)
      (effects (font (size 1.27 1.27) (thickness 0.15)) (justify left bottom) hide)
    )
    (property "Author" "Antmicro" (at 248.92 116.84 0)
      (effects (font (size 1.27 1.27) (thickness 0.15)) (justify left bottom) hide)
    )
    (property "Voltage" "50V" (at 246.38 116.84 0)
      (effects (font (size 1.27 1.27)) (justify left bottom) hide)
    )
    (property "Dielectric" "X5R" (at 243.84 116.84 0)
      (effects (font (size 1.27 1.27)) (justify left bottom) hide)
    )
    (pin "1")
    (pin "2")
    (instances
      (project "kria-k26-devboard"
        (path ""
          (reference "C163") (unit 1)
        )
      )
    )
  )

  (symbol (lib_id "kria-k26-devboard:GND") (at 274.32 101.6 0) (unit 1)
    (in_bom yes) (on_board yes) (dnp no) (fields_autoplaced)
    (property "Reference" "#PWR0345" (at 274.32 107.95 0)
      (effects (font (size 1.27 1.27)) hide)
    )
    (property "Value" "GND" (at 274.32 107.188 0)
      (effects (font (size 1.27 1.27)))
    )
    (property "Footprint" "" (at 283.21 109.22 0)
      (effects (font (size 1.27 1.27) (thickness 0.15)) (justify left bottom) hide)
    )
    (property "Datasheet" "" (at 283.21 114.3 0)
      (effects (font (size 1.27 1.27) (thickness 0.15)) (justify left bottom) hide)
    )
    (property "Author" "Antmicro" (at 283.21 109.22 0)
      (effects (font (size 1.27 1.27) (thickness 0.15)) (justify left bottom) hide)
    )
    (property "License" "Apache-2.0" (at 283.21 111.76 0)
      (effects (font (size 1.27 1.27) (thickness 0.15)) (justify left bottom) hide)
    )
    (pin "1")
    (instances
      (project "kria-k26-devboard"
        (path ""
          (reference "#PWR0345") (unit 1)
        )
      )
    )
  )

  (symbol (lib_id "kria-k26-devboard:C_100n_0402") (at 271.78 186.055 270) (unit 1)
    (in_bom yes) (on_board yes) (dnp no) (fields_autoplaced)
    (property "Reference" "C164" (at 274.32 187.3313 90)
      (effects (font (size 1.524 1.524)) (justify left))
    )
    (property "Value" "C_100n_0402" (at 267.97 186.055 0)
      (effects (font (size 1.27 1.27) (thickness 0.15)) (justify left bottom) hide)
    )
    (property "Footprint" "kria-k26-devboard-footprints:C_0402_1005Metric" (at 276.86 191.135 0)
      (effects (font (size 1.27 1.27) (thickness 0.15)) (justify left bottom) hide)
    )
    (property "Datasheet" "https://search.murata.co.jp/Ceramy/image/img/A01X/G101/ENG/GRM155R61H104KE14-01.pdf" (at 271.78 186.055 0)
      (effects (font (size 1.27 1.27) (thickness 0.15)) (justify left bottom) hide)
    )
    (property "Manufacturer" "Murata" (at 281.94 191.135 0)
      (effects (font (size 1.27 1.27) (thickness 0.15)) (justify left bottom) hide)
    )
    (property "MPN" "GRM155R61H104KE14D" (at 279.4 191.135 0)
      (effects (font (size 1.27 1.27) (thickness 0.15)) (justify left bottom) hide)
    )
    (property "Val" "100n" (at 274.32 190.5062 90)
      (effects (font (size 1.27 1.27) (thickness 0.15)) (justify left))
    )
    (property "License" "Apache-2.0" (at 248.92 206.375 0)
      (effects (font (size 1.27 1.27) (thickness 0.15)) (justify left bottom) hide)
    )
    (property "Author" "Antmicro" (at 246.38 206.375 0)
      (effects (font (size 1.27 1.27) (thickness 0.15)) (justify left bottom) hide)
    )
    (property "Voltage" "50V" (at 243.84 206.375 0)
      (effects (font (size 1.27 1.27)) (justify left bottom) hide)
    )
    (property "Dielectric" "X5R" (at 241.3 206.375 0)
      (effects (font (size 1.27 1.27)) (justify left bottom) hide)
    )
    (pin "1")
    (pin "2")
    (instances
      (project "kria-k26-devboard"
        (path ""
          (reference "C164") (unit 1)
        )
      )
    )
  )

  (symbol (lib_id "kria-k26-devboard:GND") (at 271.78 191.135 0) (unit 1)
    (in_bom yes) (on_board yes) (dnp no) (fields_autoplaced)
    (property "Reference" "#PWR0346" (at 271.78 197.485 0)
      (effects (font (size 1.27 1.27)) hide)
    )
    (property "Value" "GND" (at 271.78 196.215 0)
      (effects (font (size 1.27 1.27)))
    )
    (property "Footprint" "" (at 280.67 198.755 0)
      (effects (font (size 1.27 1.27) (thickness 0.15)) (justify left bottom) hide)
    )
    (property "Datasheet" "" (at 280.67 203.835 0)
      (effects (font (size 1.27 1.27) (thickness 0.15)) (justify left bottom) hide)
    )
    (property "Author" "Antmicro" (at 280.67 198.755 0)
      (effects (font (size 1.27 1.27) (thickness 0.15)) (justify left bottom) hide)
    )
    (property "License" "Apache-2.0" (at 280.67 201.295 0)
      (effects (font (size 1.27 1.27) (thickness 0.15)) (justify left bottom) hide)
    )
    (pin "1")
    (instances
      (project "kria-k26-devboard"
        (path ""
          (reference "#PWR0346") (unit 1)
        )
      )
    )
  )

  (symbol (lib_id "kria-k26-devboard:C_100n_0402") (at 351.79 187.325 270) (unit 1)
    (in_bom yes) (on_board yes) (dnp no) (fields_autoplaced)
    (property "Reference" "C166" (at 354.33 188.6013 90)
      (effects (font (size 1.524 1.524)) (justify left))
    )
    (property "Value" "C_100n_0402" (at 347.98 187.325 0)
      (effects (font (size 1.27 1.27) (thickness 0.15)) (justify left bottom) hide)
    )
    (property "Footprint" "kria-k26-devboard-footprints:C_0402_1005Metric" (at 356.87 192.405 0)
      (effects (font (size 1.27 1.27) (thickness 0.15)) (justify left bottom) hide)
    )
    (property "Datasheet" "https://search.murata.co.jp/Ceramy/image/img/A01X/G101/ENG/GRM155R61H104KE14-01.pdf" (at 351.79 187.325 0)
      (effects (font (size 1.27 1.27) (thickness 0.15)) (justify left bottom) hide)
    )
    (property "Manufacturer" "Murata" (at 361.95 192.405 0)
      (effects (font (size 1.27 1.27) (thickness 0.15)) (justify left bottom) hide)
    )
    (property "MPN" "GRM155R61H104KE14D" (at 359.41 192.405 0)
      (effects (font (size 1.27 1.27) (thickness 0.15)) (justify left bottom) hide)
    )
    (property "Val" "100n" (at 354.33 191.7762 90)
      (effects (font (size 1.27 1.27) (thickness 0.15)) (justify left))
    )
    (property "License" "Apache-2.0" (at 328.93 207.645 0)
      (effects (font (size 1.27 1.27) (thickness 0.15)) (justify left bottom) hide)
    )
    (property "Author" "Antmicro" (at 326.39 207.645 0)
      (effects (font (size 1.27 1.27) (thickness 0.15)) (justify left bottom) hide)
    )
    (property "Voltage" "50V" (at 323.85 207.645 0)
      (effects (font (size 1.27 1.27)) (justify left bottom) hide)
    )
    (property "Dielectric" "X5R" (at 321.31 207.645 0)
      (effects (font (size 1.27 1.27)) (justify left bottom) hide)
    )
    (pin "1")
    (pin "2")
    (instances
      (project "kria-k26-devboard"
        (path ""
          (reference "C166") (unit 1)
        )
      )
    )
  )

  (symbol (lib_id "kria-k26-devboard:GND") (at 351.79 192.405 0) (unit 1)
    (in_bom yes) (on_board yes) (dnp no) (fields_autoplaced)
    (property "Reference" "#PWR0356" (at 351.79 198.755 0)
      (effects (font (size 1.27 1.27)) hide)
    )
    (property "Value" "GND" (at 351.79 197.485 0)
      (effects (font (size 1.27 1.27)))
    )
    (property "Footprint" "" (at 360.68 200.025 0)
      (effects (font (size 1.27 1.27) (thickness 0.15)) (justify left bottom) hide)
    )
    (property "Datasheet" "" (at 360.68 205.105 0)
      (effects (font (size 1.27 1.27) (thickness 0.15)) (justify left bottom) hide)
    )
    (property "Author" "Antmicro" (at 360.68 200.025 0)
      (effects (font (size 1.27 1.27) (thickness 0.15)) (justify left bottom) hide)
    )
    (property "License" "Apache-2.0" (at 360.68 202.565 0)
      (effects (font (size 1.27 1.27) (thickness 0.15)) (justify left bottom) hide)
    )
    (pin "1")
    (instances
      (project "kria-k26-devboard"
        (path ""
          (reference "#PWR0356") (unit 1)
        )
      )
    )
  )

  (symbol (lib_id "kria-k26-devboard:GND") (at 297.18 200.66 0) (unit 1)
    (in_bom yes) (on_board yes) (dnp no) (fields_autoplaced)
    (property "Reference" "#PWR0349" (at 297.18 207.01 0)
      (effects (font (size 1.27 1.27)) hide)
    )
    (property "Value" "GND" (at 297.18 205.74 0)
      (effects (font (size 1.27 1.27)))
    )
    (property "Footprint" "" (at 306.07 208.28 0)
      (effects (font (size 1.27 1.27) (thickness 0.15)) (justify left bottom) hide)
    )
    (property "Datasheet" "" (at 306.07 213.36 0)
      (effects (font (size 1.27 1.27) (thickness 0.15)) (justify left bottom) hide)
    )
    (property "Author" "Antmicro" (at 306.07 208.28 0)
      (effects (font (size 1.27 1.27) (thickness 0.15)) (justify left bottom) hide)
    )
    (property "License" "Apache-2.0" (at 306.07 210.82 0)
      (effects (font (size 1.27 1.27) (thickness 0.15)) (justify left bottom) hide)
    )
    (pin "1")
    (instances
      (project "kria-k26-devboard"
        (path ""
          (reference "#PWR0349") (unit 1)
        )
      )
    )
  )

  (symbol (lib_id "kria-k26-devboard:FT4232HP_QFN") (at 186.69 115.57 0) (unit 1)
    (in_bom yes) (on_board yes) (dnp no) (fields_autoplaced)
    (property "Reference" "U40" (at 207.01 106.68 0)
      (effects (font (size 1.524 1.524)))
    )
    (property "Value" "FT4232HP_QFN" (at 242.57 120.65 0)
      (effects (font (size 1.27 1.27) (thickness 0.15)) (justify left bottom) hide)
    )
    (property "Footprint" "kria-k26-devboard-footprints:QFN-68-1EP_8x8mm_P0.4mm" (at 242.57 123.19 0)
      (effects (font (size 1.27 1.27) (thickness 0.15)) (justify left bottom) hide)
    )
    (property "Datasheet" "https://ftdichip.com/wp-content/uploads/2021/11/DS_FT4233HP.pdf" (at 242.57 125.73 0)
      (effects (font (size 1.27 1.27) (thickness 0.15)) (justify left bottom) hide)
    )
    (property "Manufacturer" "FTDI Chip" (at 242.57 128.27 0)
      (effects (font (size 1.27 1.27) (thickness 0.15)) (justify left bottom) hide)
    )
    (property "MPN" "FT4232HPQ-TRAY" (at 207.01 110.49 0)
      (effects (font (size 1.27 1.27) (thickness 0.15)))
    )
    (property "Author" "Antmicro" (at 242.57 133.35 0)
      (effects (font (size 1.27 1.27) (thickness 0.15)) (justify left bottom) hide)
    )
    (property "License" "Apache-2.0" (at 242.57 135.89 0)
      (effects (font (size 1.27 1.27) (thickness 0.15)) (justify left bottom) hide)
    )
    (pin "1")
    (pin "10")
    (pin "11")
    (pin "12")
    (pin "13")
    (pin "14")
    (pin "15")
    (pin "16")
    (pin "17")
    (pin "18")
    (pin "19")
    (pin "2")
    (pin "20")
    (pin "21")
    (pin "22")
    (pin "23")
    (pin "24")
    (pin "25")
    (pin "26")
    (pin "27")
    (pin "28")
    (pin "29")
    (pin "3")
    (pin "30")
    (pin "31")
    (pin "32")
    (pin "33")
    (pin "34")
    (pin "35")
    (pin "36")
    (pin "37")
    (pin "38")
    (pin "39")
    (pin "4")
    (pin "40")
    (pin "41")
    (pin "42")
    (pin "43")
    (pin "44")
    (pin "45")
    (pin "46")
    (pin "47")
    (pin "48")
    (pin "49")
    (pin "5")
    (pin "50")
    (pin "51")
    (pin "52")
    (pin "53")
    (pin "54")
    (pin "55")
    (pin "56")
    (pin "57")
    (pin "58")
    (pin "59")
    (pin "6")
    (pin "60")
    (pin "61")
    (pin "62")
    (pin "63")
    (pin "64")
    (pin "65")
    (pin "66")
    (pin "67")
    (pin "68")
    (pin "7")
    (pin "8")
    (pin "9")
    (pin "EP")
    (instances
      (project "kria-k26-devboard"
        (path ""
          (reference "U40") (unit 1)
        )
      )
    )
  )

  (symbol (lib_id "kria-k26-devboard:R_10k_0402") (at 177.038 253.365 270) (unit 1)
    (in_bom yes) (on_board yes) (dnp no)
    (property "Reference" "R108" (at 178.308 255.27 90)
      (effects (font (size 1.524 1.524)) (justify left))
    )
    (property "Value" "R_10k_0402" (at 173.228 253.365 0)
      (effects (font (size 1.27 1.27) (thickness 0.15)) (justify left bottom) hide)
    )
    (property "Footprint" "kria-k26-devboard-footprints:R_0402_1005Metric" (at 182.118 258.445 0)
      (effects (font (size 1.27 1.27) (thickness 0.15)) (justify left bottom) hide)
    )
    (property "Datasheet" "https://www.bourns.com/docs/product-datasheets/cr.pdf" (at 177.038 253.365 0)
      (effects (font (size 1.27 1.27) (thickness 0.15)) (justify left bottom) hide)
    )
    (property "Manufacturer" "Bourns" (at 187.198 258.445 0)
      (effects (font (size 1.27 1.27) (thickness 0.15)) (justify left bottom) hide)
    )
    (property "MPN" "CR0402-FX-1002GLF" (at 184.658 258.445 0)
      (effects (font (size 1.27 1.27) (thickness 0.15)) (justify left bottom) hide)
    )
    (property "Val" "10k" (at 178.308 257.1749 90)
      (effects (font (size 1.27 1.27) (thickness 0.15)) (justify left))
    )
    (property "License" "Apache-2.0" (at 151.638 273.685 0)
      (effects (font (size 1.27 1.27) (thickness 0.15)) (justify left bottom) hide)
    )
    (property "Author" "Antmicro" (at 149.098 273.685 0)
      (effects (font (size 1.27 1.27) (thickness 0.15)) (justify left bottom) hide)
    )
    (property "Tolerance" "1%" (at 166.878 273.685 0)
      (effects (font (size 1.27 1.27)) (justify left bottom) hide)
    )
    (pin "1")
    (pin "2")
    (instances
      (project "kria-k26-devboard"
        (path ""
          (reference "R108") (unit 1)
        )
      )
    )
  )

  (symbol (lib_id "kria-k26-devboard:R_10k_0402") (at 187.198 253.365 270) (unit 1)
    (in_bom yes) (on_board yes) (dnp no)
    (property "Reference" "R110" (at 188.468 255.27 90)
      (effects (font (size 1.524 1.524)) (justify left))
    )
    (property "Value" "R_10k_0402" (at 183.388 253.365 0)
      (effects (font (size 1.27 1.27) (thickness 0.15)) (justify left bottom) hide)
    )
    (property "Footprint" "kria-k26-devboard-footprints:R_0402_1005Metric" (at 192.278 258.445 0)
      (effects (font (size 1.27 1.27) (thickness 0.15)) (justify left bottom) hide)
    )
    (property "Datasheet" "https://www.bourns.com/docs/product-datasheets/cr.pdf" (at 187.198 253.365 0)
      (effects (font (size 1.27 1.27) (thickness 0.15)) (justify left bottom) hide)
    )
    (property "Manufacturer" "Bourns" (at 197.358 258.445 0)
      (effects (font (size 1.27 1.27) (thickness 0.15)) (justify left bottom) hide)
    )
    (property "MPN" "CR0402-FX-1002GLF" (at 194.818 258.445 0)
      (effects (font (size 1.27 1.27) (thickness 0.15)) (justify left bottom) hide)
    )
    (property "Val" "10k" (at 188.468 257.1749 90)
      (effects (font (size 1.27 1.27) (thickness 0.15)) (justify left))
    )
    (property "License" "Apache-2.0" (at 161.798 273.685 0)
      (effects (font (size 1.27 1.27) (thickness 0.15)) (justify left bottom) hide)
    )
    (property "Author" "Antmicro" (at 159.258 273.685 0)
      (effects (font (size 1.27 1.27) (thickness 0.15)) (justify left bottom) hide)
    )
    (property "Tolerance" "1%" (at 177.038 273.685 0)
      (effects (font (size 1.27 1.27)) (justify left bottom) hide)
    )
    (pin "1")
    (pin "2")
    (instances
      (project "kria-k26-devboard"
        (path ""
          (reference "R110") (unit 1)
        )
      )
    )
  )

  (symbol (lib_id "kria-k26-devboard:Resonator_12MHz_ABM8G") (at 106.68 154.94 0) (unit 1)
    (in_bom yes) (on_board yes) (dnp no) (fields_autoplaced)
    (property "Reference" "Y7" (at 110.49 147.32 0)
      (effects (font (size 1.27 1.27)))
    )
    (property "Value" "Resonator_12MHz_ABM8G" (at 121.92 167.64 0)
      (effects (font (size 1.27 1.27) (thickness 0.15)) (justify left bottom) hide)
    )
    (property "Footprint" "kria-k26-devboard-footprints:Oscillator_SMD_Geyer_KX-7-4Pin_3.2x2.5mm" (at 121.92 170.18 0)
      (effects (font (size 1.27 1.27) (thickness 0.15)) (justify left bottom) hide)
    )
    (property "Datasheet" "https://abracon.com/Resonators/ABM8G.pdf" (at 121.92 172.72 0)
      (effects (font (size 1.27 1.27) (thickness 0.15)) (justify left bottom) hide)
    )
    (property "MPN" "ABM8G-12.000MHZ-18-D2Y-T" (at 121.92 162.56 0)
      (effects (font (size 1.27 1.27) (thickness 0.15)) (justify left bottom) hide)
    )
    (property "Manufacturer" "Abracon" (at 121.92 175.26 0)
      (effects (font (size 1.27 1.27) (thickness 0.15)) (justify left bottom) hide)
    )
    (property "Val" "12 MHz" (at 110.49 149.86 0)
      (effects (font (size 1.27 1.27) (thickness 0.15)))
    )
    (property "Author" "Antmicro" (at 121.92 177.8 0)
      (effects (font (size 1.27 1.27) (thickness 0.15)) (justify left bottom) hide)
    )
    (property "License" "Apache-2.0" (at 121.92 180.34 0)
      (effects (font (size 1.27 1.27) (thickness 0.15)) (justify left bottom) hide)
    )
    (pin "1")
    (pin "2")
    (pin "3")
    (pin "4")
    (instances
      (project "kria-k26-devboard"
        (path ""
          (reference "Y7") (unit 1)
        )
      )
    )
  )

  (symbol (lib_id "kria-k26-devboard:GND") (at 185.42 219.075 0) (unit 1)
    (in_bom yes) (on_board yes) (dnp no) (fields_autoplaced)
    (property "Reference" "#PWR0335" (at 185.42 225.425 0)
      (effects (font (size 1.27 1.27)) hide)
    )
    (property "Value" "GND" (at 185.42 224.155 0)
      (effects (font (size 1.27 1.27)))
    )
    (property "Footprint" "" (at 194.31 226.695 0)
      (effects (font (size 1.27 1.27) (thickness 0.15)) (justify left bottom) hide)
    )
    (property "Datasheet" "" (at 194.31 231.775 0)
      (effects (font (size 1.27 1.27) (thickness 0.15)) (justify left bottom) hide)
    )
    (property "Author" "Antmicro" (at 194.31 226.695 0)
      (effects (font (size 1.27 1.27) (thickness 0.15)) (justify left bottom) hide)
    )
    (property "License" "Apache-2.0" (at 194.31 229.235 0)
      (effects (font (size 1.27 1.27) (thickness 0.15)) (justify left bottom) hide)
    )
    (pin "1")
    (instances
      (project "kria-k26-devboard"
        (path ""
          (reference "#PWR0335") (unit 1)
        )
      )
    )
  )

  (symbol (lib_id "kria-k26-devboard:C_18p_0402") (at 102.235 156.21 270) (unit 1)
    (in_bom yes) (on_board yes) (dnp no) (fields_autoplaced)
    (property "Reference" "C154" (at 99.06 157.4863 90)
      (effects (font (size 1.524 1.524)) (justify right))
    )
    (property "Value" "C_18p_0402" (at 98.425 156.21 0)
      (effects (font (size 1.27 1.27) (thickness 0.15)) (justify left bottom) hide)
    )
    (property "Footprint" "kria-k26-devboard-footprints:C_0402_1005Metric" (at 107.315 161.29 0)
      (effects (font (size 1.27 1.27) (thickness 0.15)) (justify left bottom) hide)
    )
    (property "Datasheet" " " (at 102.235 156.21 0)
      (effects (font (size 1.27 1.27) (thickness 0.15)) (justify left bottom) hide)
    )
    (property "Manufacturer" "Multicomp" (at 112.395 161.29 0)
      (effects (font (size 1.27 1.27) (thickness 0.15)) (justify left bottom) hide)
    )
    (property "MPN" "MC0402N180J500CT" (at 109.855 161.29 0)
      (effects (font (size 1.27 1.27) (thickness 0.15)) (justify left bottom) hide)
    )
    (property "Val" "18p" (at 99.06 160.6612 90)
      (effects (font (size 1.27 1.27) (thickness 0.15)) (justify right))
    )
    (property "License" "Apache-2.0" (at 79.375 176.53 0)
      (effects (font (size 1.27 1.27) (thickness 0.15)) (justify left bottom) hide)
    )
    (property "Author" "Antmicro" (at 76.835 176.53 0)
      (effects (font (size 1.27 1.27) (thickness 0.15)) (justify left bottom) hide)
    )
    (property "Voltage" "" (at 74.295 176.53 0)
      (effects (font (size 1.27 1.27)) (justify left bottom) hide)
    )
    (property "Dielectric" "" (at 71.755 176.53 0)
      (effects (font (size 1.27 1.27)) (justify left bottom) hide)
    )
    (pin "1")
    (pin "2")
    (instances
      (project "kria-k26-devboard"
        (path ""
          (reference "C154") (unit 1)
        )
      )
    )
  )

  (symbol (lib_id "kria-k26-devboard:C_18p_0402") (at 116.84 156.21 270) (unit 1)
    (in_bom yes) (on_board yes) (dnp no) (fields_autoplaced)
    (property "Reference" "C156" (at 119.38 157.4863 90)
      (effects (font (size 1.524 1.524)) (justify left))
    )
    (property "Value" "C_18p_0402" (at 113.03 156.21 0)
      (effects (font (size 1.27 1.27) (thickness 0.15)) (justify left bottom) hide)
    )
    (property "Footprint" "kria-k26-devboard-footprints:C_0402_1005Metric" (at 121.92 161.29 0)
      (effects (font (size 1.27 1.27) (thickness 0.15)) (justify left bottom) hide)
    )
    (property "Datasheet" " " (at 116.84 156.21 0)
      (effects (font (size 1.27 1.27) (thickness 0.15)) (justify left bottom) hide)
    )
    (property "Manufacturer" "Multicomp" (at 127 161.29 0)
      (effects (font (size 1.27 1.27) (thickness 0.15)) (justify left bottom) hide)
    )
    (property "MPN" "MC0402N180J500CT" (at 124.46 161.29 0)
      (effects (font (size 1.27 1.27) (thickness 0.15)) (justify left bottom) hide)
    )
    (property "Val" "18p" (at 119.38 160.6612 90)
      (effects (font (size 1.27 1.27) (thickness 0.15)) (justify left))
    )
    (property "License" "Apache-2.0" (at 93.98 176.53 0)
      (effects (font (size 1.27 1.27) (thickness 0.15)) (justify left bottom) hide)
    )
    (property "Author" "Antmicro" (at 91.44 176.53 0)
      (effects (font (size 1.27 1.27) (thickness 0.15)) (justify left bottom) hide)
    )
    (property "Voltage" "" (at 88.9 176.53 0)
      (effects (font (size 1.27 1.27)) (justify left bottom) hide)
    )
    (property "Dielectric" "" (at 86.36 176.53 0)
      (effects (font (size 1.27 1.27)) (justify left bottom) hide)
    )
    (pin "1")
    (pin "2")
    (instances
      (project "kria-k26-devboard"
        (path ""
          (reference "C156") (unit 1)
        )
      )
    )
  )

  (symbol (lib_id "kria-k26-devboard:GND") (at 102.235 161.29 0) (unit 1)
    (in_bom yes) (on_board yes) (dnp no) (fields_autoplaced)
    (property "Reference" "#PWR0329" (at 102.235 167.64 0)
      (effects (font (size 1.27 1.27)) hide)
    )
    (property "Value" "GND" (at 102.235 165.735 0)
      (effects (font (size 1.27 1.27)))
    )
    (property "Footprint" "" (at 111.125 168.91 0)
      (effects (font (size 1.27 1.27) (thickness 0.15)) (justify left bottom) hide)
    )
    (property "Datasheet" "" (at 111.125 173.99 0)
      (effects (font (size 1.27 1.27) (thickness 0.15)) (justify left bottom) hide)
    )
    (property "Author" "Antmicro" (at 111.125 168.91 0)
      (effects (font (size 1.27 1.27) (thickness 0.15)) (justify left bottom) hide)
    )
    (property "License" "Apache-2.0" (at 111.125 171.45 0)
      (effects (font (size 1.27 1.27) (thickness 0.15)) (justify left bottom) hide)
    )
    (pin "1")
    (instances
      (project "kria-k26-devboard"
        (path ""
          (reference "#PWR0329") (unit 1)
        )
      )
    )
  )

  (symbol (lib_id "kria-k26-devboard:GND") (at 142.748 273.812 0) (unit 1)
    (in_bom yes) (on_board yes) (dnp no) (fields_autoplaced)
    (property "Reference" "#PWR0336" (at 142.748 280.162 0)
      (effects (font (size 1.27 1.27)) hide)
    )
    (property "Value" "GND" (at 142.748 278.892 0)
      (effects (font (size 1.27 1.27)))
    )
    (property "Footprint" "" (at 151.638 281.432 0)
      (effects (font (size 1.27 1.27) (thickness 0.15)) (justify left bottom) hide)
    )
    (property "Datasheet" "" (at 151.638 286.512 0)
      (effects (font (size 1.27 1.27) (thickness 0.15)) (justify left bottom) hide)
    )
    (property "Author" "Antmicro" (at 151.638 281.432 0)
      (effects (font (size 1.27 1.27) (thickness 0.15)) (justify left bottom) hide)
    )
    (property "License" "Apache-2.0" (at 151.638 283.972 0)
      (effects (font (size 1.27 1.27) (thickness 0.15)) (justify left bottom) hide)
    )
    (pin "1")
    (instances
      (project "kria-k26-devboard"
        (path ""
          (reference "#PWR0336") (unit 1)
        )
      )
    )
  )

  (symbol (lib_id "kria-k26-devboard:C_100n_0402") (at 132.588 265.43 270) (unit 1)
    (in_bom yes) (on_board yes) (dnp no) (fields_autoplaced)
    (property "Reference" "C157" (at 135.763 266.7063 90)
      (effects (font (size 1.524 1.524)) (justify left))
    )
    (property "Value" "C_100n_0402" (at 128.778 265.43 0)
      (effects (font (size 1.27 1.27) (thickness 0.15)) (justify left bottom) hide)
    )
    (property "Footprint" "kria-k26-devboard-footprints:C_0402_1005Metric" (at 137.668 270.51 0)
      (effects (font (size 1.27 1.27) (thickness 0.15)) (justify left bottom) hide)
    )
    (property "Datasheet" "https://search.murata.co.jp/Ceramy/image/img/A01X/G101/ENG/GRM155R61H104KE14-01.pdf" (at 132.588 265.43 0)
      (effects (font (size 1.27 1.27) (thickness 0.15)) (justify left bottom) hide)
    )
    (property "Manufacturer" "Murata" (at 142.748 270.51 0)
      (effects (font (size 1.27 1.27) (thickness 0.15)) (justify left bottom) hide)
    )
    (property "MPN" "GRM155R61H104KE14D" (at 140.208 270.51 0)
      (effects (font (size 1.27 1.27) (thickness 0.15)) (justify left bottom) hide)
    )
    (property "Val" "100n" (at 135.763 269.8812 90)
      (effects (font (size 1.27 1.27) (thickness 0.15)) (justify left))
    )
    (property "License" "Apache-2.0" (at 109.728 285.75 0)
      (effects (font (size 1.27 1.27) (thickness 0.15)) (justify left bottom) hide)
    )
    (property "Author" "Antmicro" (at 107.188 285.75 0)
      (effects (font (size 1.27 1.27) (thickness 0.15)) (justify left bottom) hide)
    )
    (property "Voltage" "50V" (at 104.648 285.75 0)
      (effects (font (size 1.27 1.27)) (justify left bottom) hide)
    )
    (property "Dielectric" "X5R" (at 102.108 285.75 0)
      (effects (font (size 1.27 1.27)) (justify left bottom) hide)
    )
    (pin "1")
    (pin "2")
    (instances
      (project "kria-k26-devboard"
        (path ""
          (reference "C157") (unit 1)
        )
      )
    )
  )

  (symbol (lib_id "kria-k26-devboard:GND") (at 132.588 270.51 0) (unit 1)
    (in_bom yes) (on_board yes) (dnp no) (fields_autoplaced)
    (property "Reference" "#PWR0332" (at 132.588 276.86 0)
      (effects (font (size 1.27 1.27)) hide)
    )
    (property "Value" "GND" (at 132.588 275.59 0)
      (effects (font (size 1.27 1.27)))
    )
    (property "Footprint" "" (at 141.478 278.13 0)
      (effects (font (size 1.27 1.27) (thickness 0.15)) (justify left bottom) hide)
    )
    (property "Datasheet" "" (at 141.478 283.21 0)
      (effects (font (size 1.27 1.27) (thickness 0.15)) (justify left bottom) hide)
    )
    (property "Author" "Antmicro" (at 141.478 278.13 0)
      (effects (font (size 1.27 1.27) (thickness 0.15)) (justify left bottom) hide)
    )
    (property "License" "Apache-2.0" (at 141.478 280.67 0)
      (effects (font (size 1.27 1.27) (thickness 0.15)) (justify left bottom) hide)
    )
    (pin "1")
    (instances
      (project "kria-k26-devboard"
        (path ""
          (reference "#PWR0332") (unit 1)
        )
      )
    )
  )

  (symbol (lib_id "kria-k26-devboard:GND") (at 42.545 72.39 0) (unit 1)
    (in_bom yes) (on_board yes) (dnp no) (fields_autoplaced)
    (property "Reference" "#PWR0319" (at 42.545 78.74 0)
      (effects (font (size 1.27 1.27)) hide)
    )
    (property "Value" "GND" (at 42.545 76.835 0)
      (effects (font (size 1.27 1.27)))
    )
    (property "Footprint" "" (at 51.435 80.01 0)
      (effects (font (size 1.27 1.27) (thickness 0.15)) (justify left bottom) hide)
    )
    (property "Datasheet" "" (at 51.435 85.09 0)
      (effects (font (size 1.27 1.27) (thickness 0.15)) (justify left bottom) hide)
    )
    (property "Author" "Antmicro" (at 51.435 80.01 0)
      (effects (font (size 1.27 1.27) (thickness 0.15)) (justify left bottom) hide)
    )
    (property "License" "Apache-2.0" (at 51.435 82.55 0)
      (effects (font (size 1.27 1.27) (thickness 0.15)) (justify left bottom) hide)
    )
    (pin "1")
    (instances
      (project "kria-k26-devboard"
        (path ""
          (reference "#PWR0319") (unit 1)
        )
      )
    )
  )

  (symbol (lib_id "kria-k26-devboard:R_5k11_0402") (at 41.275 40.64 0) (unit 1)
    (in_bom yes) (on_board yes) (dnp no)
    (property "Reference" "R99" (at 39.37 39.37 0)
      (effects (font (size 1.524 1.524)))
    )
    (property "Value" "R_5k11_0402" (at 41.275 44.45 0)
      (effects (font (size 1.27 1.27) (thickness 0.15)) (justify left bottom) hide)
    )
    (property "Footprint" "kria-k26-devboard-footprints:R_0402_1005Metric" (at 46.355 35.56 0)
      (effects (font (size 1.27 1.27) (thickness 0.15)) (justify left bottom) hide)
    )
    (property "Datasheet" "https://www.bourns.com/docs/product-datasheets/cr.pdf" (at 41.275 40.64 0)
      (effects (font (size 1.27 1.27) (thickness 0.15)) (justify left bottom) hide)
    )
    (property "Manufacturer" "Bourns" (at 46.355 30.48 0)
      (effects (font (size 1.27 1.27) (thickness 0.15)) (justify left bottom) hide)
    )
    (property "MPN" "CR0402-FX-5111GLF" (at 46.355 33.02 0)
      (effects (font (size 1.27 1.27) (thickness 0.15)) (justify left bottom) hide)
    )
    (property "Val" "5k11" (at 48.26 39.37 0)
      (effects (font (size 1.27 1.27) (thickness 0.15)))
    )
    (property "License" "Apache-2.0" (at 61.595 66.04 0)
      (effects (font (size 1.27 1.27) (thickness 0.15)) (justify left bottom) hide)
    )
    (property "Author" "Antmicro" (at 61.595 68.58 0)
      (effects (font (size 1.27 1.27) (thickness 0.15)) (justify left bottom) hide)
    )
    (property "Tolerance" "1%" (at 61.595 50.8 0)
      (effects (font (size 1.27 1.27)) (justify left bottom) hide)
    )
    (pin "1")
    (pin "2")
    (instances
      (project "kria-k26-devboard"
        (path ""
          (reference "R99") (unit 1)
        )
      )
    )
  )

  (symbol (lib_id "kria-k26-devboard:GND") (at 43.18 53.975 0) (unit 1)
    (in_bom yes) (on_board yes) (dnp no) (fields_autoplaced)
    (property "Reference" "#PWR0320" (at 43.18 60.325 0)
      (effects (font (size 1.27 1.27)) hide)
    )
    (property "Value" "GND" (at 43.18 59.055 0)
      (effects (font (size 1.27 1.27)))
    )
    (property "Footprint" "" (at 52.07 61.595 0)
      (effects (font (size 1.27 1.27) (thickness 0.15)) (justify left bottom) hide)
    )
    (property "Datasheet" "" (at 52.07 66.675 0)
      (effects (font (size 1.27 1.27) (thickness 0.15)) (justify left bottom) hide)
    )
    (property "Author" "Antmicro" (at 52.07 61.595 0)
      (effects (font (size 1.27 1.27) (thickness 0.15)) (justify left bottom) hide)
    )
    (property "License" "Apache-2.0" (at 52.07 64.135 0)
      (effects (font (size 1.27 1.27) (thickness 0.15)) (justify left bottom) hide)
    )
    (pin "1")
    (instances
      (project "kria-k26-devboard"
        (path ""
          (reference "#PWR0320") (unit 1)
        )
      )
    )
  )

  (symbol (lib_id "kria-k26-devboard:82400152") (at 44.45 48.26 0) (unit 1)
    (in_bom yes) (on_board yes) (dnp no) (fields_autoplaced)
    (property "Reference" "U37" (at 52.07 57.15 0)
      (effects (font (size 1.27 1.27)))
    )
    (property "Value" "82400152" (at 52.07 59.69 0)
      (effects (font (size 1.27 1.27) (thickness 0.15)))
    )
    (property "Footprint" "kria-k26-devboard-footprints:SOT-563" (at 44.45 53.34 0)
      (effects (font (size 1.27 1.27) (thickness 0.15)) (justify left bottom) hide)
    )
    (property "Datasheet" "https://www.we-online.com/components/products/datasheet/82400152.pdf" (at 44.45 54.61 0)
      (effects (font (size 1.27 1.27) (thickness 0.15)) (justify left bottom) hide)
    )
    (property "MPN" "82400152" (at 35.56 58.42 0)
      (effects (font (size 1.27 1.27) (thickness 0.15)) (justify left bottom) hide)
    )
    (property "Manufacturer" "Würth Elektronik" (at 38.1 55.88 0)
      (effects (font (size 1.27 1.27) (thickness 0.15)) (justify left bottom) hide)
    )
    (property "Author" "Antmicro" (at 74.93 68.58 0)
      (effects (font (size 1.27 1.27) (thickness 0.15)) (justify left bottom) hide)
    )
    (property "License" "Apache-2.0" (at 74.93 71.12 0)
      (effects (font (size 1.27 1.27) (thickness 0.15)) (justify left bottom) hide)
    )
    (pin "1")
    (pin "2")
    (pin "3")
    (pin "4")
    (pin "5")
    (pin "6")
    (instances
      (project "kria-k26-devboard"
        (path ""
          (reference "U37") (unit 1)
        )
      )
    )
  )

  (symbol (lib_id "kria-k26-devboard:R_100k_0402") (at 159.385 46.355 270) (unit 1)
    (in_bom yes) (on_board yes) (dnp no) (fields_autoplaced)
    (property "Reference" "R104" (at 156.845 47.625 90)
      (effects (font (size 1.524 1.524)) (justify right))
    )
    (property "Value" "R_100k_0402" (at 155.575 46.355 0)
      (effects (font (size 1.27 1.27) (thickness 0.15)) (justify left bottom) hide)
    )
    (property "Footprint" "kria-k26-devboard-footprints:R_0402_1005Metric" (at 164.465 51.435 0)
      (effects (font (size 1.27 1.27) (thickness 0.15)) (justify left bottom) hide)
    )
    (property "Datasheet" "https://www.bourns.com/docs/product-datasheets/cr.pdf" (at 159.385 46.355 0)
      (effects (font (size 1.27 1.27) (thickness 0.15)) (justify left bottom) hide)
    )
    (property "Manufacturer" "Bourns" (at 169.545 51.435 0)
      (effects (font (size 1.27 1.27) (thickness 0.15)) (justify left bottom) hide)
    )
    (property "MPN" "CR0402-FX-1003GLF" (at 167.005 51.435 0)
      (effects (font (size 1.27 1.27) (thickness 0.15)) (justify left bottom) hide)
    )
    (property "Val" "100k" (at 156.845 50.7999 90)
      (effects (font (size 1.27 1.27) (thickness 0.15)) (justify right))
    )
    (property "License" "Apache-2.0" (at 133.985 66.675 0)
      (effects (font (size 1.27 1.27) (thickness 0.15)) (justify left bottom) hide)
    )
    (property "Author" "Antmicro" (at 131.445 66.675 0)
      (effects (font (size 1.27 1.27) (thickness 0.15)) (justify left bottom) hide)
    )
    (property "Tolerance" "1%" (at 149.225 66.675 0)
      (effects (font (size 1.27 1.27)) (justify left bottom) hide)
    )
    (pin "1")
    (pin "2")
    (instances
      (project "kria-k26-devboard"
        (path ""
          (reference "R104") (unit 1)
        )
      )
    )
  )

  (symbol (lib_id "kria-k26-devboard:R_15k_0603") (at 159.385 56.515 270) (unit 1)
    (in_bom yes) (on_board yes) (dnp no) (fields_autoplaced)
    (property "Reference" "R105" (at 156.845 57.785 90)
      (effects (font (size 1.524 1.524)) (justify right))
    )
    (property "Value" "R_15k_0603" (at 155.575 56.515 0)
      (effects (font (size 1.27 1.27) (thickness 0.15)) (justify left bottom) hide)
    )
    (property "Footprint" "kria-k26-devboard-footprints:R_0603_1608Metric" (at 164.465 61.595 0)
      (effects (font (size 1.27 1.27) (thickness 0.15)) (justify left bottom) hide)
    )
    (property "Datasheet" "https://www.bourns.com/docs/product-datasheets/cr.pdf" (at 159.385 56.515 0)
      (effects (font (size 1.27 1.27) (thickness 0.15)) (justify left bottom) hide)
    )
    (property "Manufacturer" "Bourns" (at 169.545 61.595 0)
      (effects (font (size 1.27 1.27) (thickness 0.15)) (justify left bottom) hide)
    )
    (property "MPN" "CR0603-FX-1502ELF" (at 167.005 61.595 0)
      (effects (font (size 1.27 1.27) (thickness 0.15)) (justify left bottom) hide)
    )
    (property "Val" "15k" (at 156.845 60.9599 90)
      (effects (font (size 1.27 1.27) (thickness 0.15)) (justify right))
    )
    (property "License" "Apache-2.0" (at 133.985 76.835 0)
      (effects (font (size 1.27 1.27) (thickness 0.15)) (justify left bottom) hide)
    )
    (property "Author" "Antmicro" (at 131.445 76.835 0)
      (effects (font (size 1.27 1.27) (thickness 0.15)) (justify left bottom) hide)
    )
    (property "Tolerance" "1%" (at 149.225 76.835 0)
      (effects (font (size 1.27 1.27)) (justify left bottom) hide)
    )
    (pin "1")
    (pin "2")
    (instances
      (project "kria-k26-devboard"
        (path ""
          (reference "R105") (unit 1)
        )
      )
    )
  )

  (symbol (lib_id "kria-k26-devboard:GND") (at 159.385 61.595 0) (unit 1)
    (in_bom yes) (on_board yes) (dnp no) (fields_autoplaced)
    (property "Reference" "#PWR0338" (at 159.385 67.945 0)
      (effects (font (size 1.27 1.27)) hide)
    )
    (property "Value" "GND" (at 159.385 66.675 0)
      (effects (font (size 1.27 1.27)))
    )
    (property "Footprint" "" (at 168.275 69.215 0)
      (effects (font (size 1.27 1.27) (thickness 0.15)) (justify left bottom) hide)
    )
    (property "Datasheet" "" (at 168.275 74.295 0)
      (effects (font (size 1.27 1.27) (thickness 0.15)) (justify left bottom) hide)
    )
    (property "Author" "Antmicro" (at 168.275 69.215 0)
      (effects (font (size 1.27 1.27) (thickness 0.15)) (justify left bottom) hide)
    )
    (property "License" "Apache-2.0" (at 168.275 71.755 0)
      (effects (font (size 1.27 1.27) (thickness 0.15)) (justify left bottom) hide)
    )
    (pin "1")
    (instances
      (project "kria-k26-devboard"
        (path ""
          (reference "#PWR0338") (unit 1)
        )
      )
    )
  )

  (symbol (lib_id "kria-k26-devboard:R_10k_0402") (at 177.165 161.29 0) (unit 1)
    (in_bom yes) (on_board yes) (dnp no)
    (property "Reference" "R103" (at 174.625 160.02 0)
      (effects (font (size 1.524 1.524)))
    )
    (property "Value" "R_10k_0402" (at 177.165 165.1 0)
      (effects (font (size 1.27 1.27) (thickness 0.15)) (justify left bottom) hide)
    )
    (property "Footprint" "kria-k26-devboard-footprints:R_0402_1005Metric" (at 182.245 156.21 0)
      (effects (font (size 1.27 1.27) (thickness 0.15)) (justify left bottom) hide)
    )
    (property "Datasheet" "https://www.bourns.com/docs/product-datasheets/cr.pdf" (at 177.165 161.29 0)
      (effects (font (size 1.27 1.27) (thickness 0.15)) (justify left bottom) hide)
    )
    (property "Manufacturer" "Bourns" (at 182.245 151.13 0)
      (effects (font (size 1.27 1.27) (thickness 0.15)) (justify left bottom) hide)
    )
    (property "MPN" "CR0402-FX-1002GLF" (at 182.245 153.67 0)
      (effects (font (size 1.27 1.27) (thickness 0.15)) (justify left bottom) hide)
    )
    (property "Val" "10k" (at 183.515 160.02 0)
      (effects (font (size 1.27 1.27) (thickness 0.15)))
    )
    (property "License" "Apache-2.0" (at 197.485 186.69 0)
      (effects (font (size 1.27 1.27) (thickness 0.15)) (justify left bottom) hide)
    )
    (property "Author" "Antmicro" (at 197.485 189.23 0)
      (effects (font (size 1.27 1.27) (thickness 0.15)) (justify left bottom) hide)
    )
    (property "Tolerance" "1%" (at 197.485 171.45 0)
      (effects (font (size 1.27 1.27)) (justify left bottom) hide)
    )
    (pin "1")
    (pin "2")
    (instances
      (project "kria-k26-devboard"
        (path ""
          (reference "R103") (unit 1)
        )
      )
    )
  )

  (symbol (lib_id "kria-k26-devboard:R_12k_0402") (at 185.42 209.55 90) (unit 1)
    (in_bom yes) (on_board yes) (dnp no)
    (property "Reference" "R102" (at 183.515 205.74 90)
      (effects (font (size 1.524 1.524)) (justify left))
    )
    (property "Value" "R_12k_0402" (at 189.23 209.55 0)
      (effects (font (size 1.27 1.27) (thickness 0.15)) (justify left bottom) hide)
    )
    (property "Footprint" "kria-k26-devboard-footprints:R_0402_1005Metric" (at 180.34 204.47 0)
      (effects (font (size 1.27 1.27) (thickness 0.15)) (justify left bottom) hide)
    )
    (property "Datasheet" "https://www.bourns.com/docs/product-datasheets/cr.pdf" (at 185.42 209.55 0)
      (effects (font (size 1.27 1.27) (thickness 0.15)) (justify left bottom) hide)
    )
    (property "Manufacturer" "Bourns" (at 175.26 204.47 0)
      (effects (font (size 1.27 1.27) (thickness 0.15)) (justify left bottom) hide)
    )
    (property "MPN" "CR0402-FX-1202GLF" (at 177.8 204.47 0)
      (effects (font (size 1.27 1.27) (thickness 0.15)) (justify left bottom) hide)
    )
    (property "Val" "12k" (at 183.515 208.28 90)
      (effects (font (size 1.27 1.27) (thickness 0.15)) (justify left))
    )
    (property "License" "Apache-2.0" (at 210.82 189.23 0)
      (effects (font (size 1.27 1.27) (thickness 0.15)) (justify left bottom) hide)
    )
    (property "Author" "Antmicro" (at 213.36 189.23 0)
      (effects (font (size 1.27 1.27) (thickness 0.15)) (justify left bottom) hide)
    )
    (property "Tolerance" "1%" (at 195.58 189.23 0)
      (effects (font (size 1.27 1.27)) (justify left bottom) hide)
    )
    (pin "1")
    (pin "2")
    (instances
      (project "kria-k26-devboard"
        (path ""
          (reference "R102") (unit 1)
        )
      )
    )
  )

  (symbol (lib_id "kria-k26-devboard:GND") (at 267.97 253.365 0) (unit 1)
    (in_bom yes) (on_board yes) (dnp no)
    (property "Reference" "#PWR0343" (at 267.97 259.715 0)
      (effects (font (size 1.27 1.27)) hide)
    )
    (property "Value" "GND" (at 266.065 257.175 0)
      (effects (font (size 1.27 1.27)) (justify left))
    )
    (property "Footprint" "" (at 276.86 260.985 0)
      (effects (font (size 1.27 1.27) (thickness 0.15)) (justify left bottom) hide)
    )
    (property "Datasheet" "" (at 276.86 266.065 0)
      (effects (font (size 1.27 1.27) (thickness 0.15)) (justify left bottom) hide)
    )
    (property "Author" "Antmicro" (at 276.86 260.985 0)
      (effects (font (size 1.27 1.27) (thickness 0.15)) (justify left bottom) hide)
    )
    (property "License" "Apache-2.0" (at 276.86 263.525 0)
      (effects (font (size 1.27 1.27) (thickness 0.15)) (justify left bottom) hide)
    )
    (pin "1")
    (instances
      (project "kria-k26-devboard"
        (path ""
          (reference "#PWR0343") (unit 1)
        )
      )
    )
  )

  (symbol (lib_id "kria-k26-devboard:C_100n_0402") (at 22.86 124.46 270) (unit 1)
    (in_bom yes) (on_board yes) (dnp no)
    (property "Reference" "C141" (at 23.495 125.095 90)
      (effects (font (size 1.524 1.524)) (justify left))
    )
    (property "Value" "C_100n_0402" (at 19.05 124.46 0)
      (effects (font (size 1.27 1.27) (thickness 0.15)) (justify left bottom) hide)
    )
    (property "Footprint" "kria-k26-devboard-footprints:C_0402_1005Metric" (at 27.94 129.54 0)
      (effects (font (size 1.27 1.27) (thickness 0.15)) (justify left bottom) hide)
    )
    (property "Datasheet" "https://search.murata.co.jp/Ceramy/image/img/A01X/G101/ENG/GRM155R61H104KE14-01.pdf" (at 22.86 124.46 0)
      (effects (font (size 1.27 1.27) (thickness 0.15)) (justify left bottom) hide)
    )
    (property "Manufacturer" "Murata" (at 33.02 129.54 0)
      (effects (font (size 1.27 1.27) (thickness 0.15)) (justify left bottom) hide)
    )
    (property "MPN" "GRM155R61H104KE14D" (at 30.48 129.54 0)
      (effects (font (size 1.27 1.27) (thickness 0.15)) (justify left bottom) hide)
    )
    (property "Val" "100n" (at 23.495 128.905 90)
      (effects (font (size 1.27 1.27) (thickness 0.15)) (justify left))
    )
    (property "License" "Apache-2.0" (at 0 144.78 0)
      (effects (font (size 1.27 1.27) (thickness 0.15)) (justify left bottom) hide)
    )
    (property "Author" "Antmicro" (at -2.54 144.78 0)
      (effects (font (size 1.27 1.27) (thickness 0.15)) (justify left bottom) hide)
    )
    (property "Voltage" "50V" (at -5.08 144.78 0)
      (effects (font (size 1.27 1.27)) (justify left bottom) hide)
    )
    (property "Dielectric" "X5R" (at -7.62 144.78 0)
      (effects (font (size 1.27 1.27)) (justify left bottom) hide)
    )
    (pin "1")
    (pin "2")
    (instances
      (project "kria-k26-devboard"
        (path ""
          (reference "C141") (unit 1)
        )
      )
    )
  )

  (symbol (lib_id "kria-k26-devboard:C_100n_0402") (at 30.48 124.46 270) (unit 1)
    (in_bom yes) (on_board yes) (dnp no)
    (property "Reference" "C143" (at 31.115 125.095 90)
      (effects (font (size 1.524 1.524)) (justify left))
    )
    (property "Value" "C_100n_0402" (at 26.67 124.46 0)
      (effects (font (size 1.27 1.27) (thickness 0.15)) (justify left bottom) hide)
    )
    (property "Footprint" "kria-k26-devboard-footprints:C_0402_1005Metric" (at 35.56 129.54 0)
      (effects (font (size 1.27 1.27) (thickness 0.15)) (justify left bottom) hide)
    )
    (property "Datasheet" "https://search.murata.co.jp/Ceramy/image/img/A01X/G101/ENG/GRM155R61H104KE14-01.pdf" (at 30.48 124.46 0)
      (effects (font (size 1.27 1.27) (thickness 0.15)) (justify left bottom) hide)
    )
    (property "Manufacturer" "Murata" (at 40.64 129.54 0)
      (effects (font (size 1.27 1.27) (thickness 0.15)) (justify left bottom) hide)
    )
    (property "MPN" "GRM155R61H104KE14D" (at 38.1 129.54 0)
      (effects (font (size 1.27 1.27) (thickness 0.15)) (justify left bottom) hide)
    )
    (property "Val" "100n" (at 31.115 128.905 90)
      (effects (font (size 1.27 1.27) (thickness 0.15)) (justify left))
    )
    (property "License" "Apache-2.0" (at 7.62 144.78 0)
      (effects (font (size 1.27 1.27) (thickness 0.15)) (justify left bottom) hide)
    )
    (property "Author" "Antmicro" (at 5.08 144.78 0)
      (effects (font (size 1.27 1.27) (thickness 0.15)) (justify left bottom) hide)
    )
    (property "Voltage" "50V" (at 2.54 144.78 0)
      (effects (font (size 1.27 1.27)) (justify left bottom) hide)
    )
    (property "Dielectric" "X5R" (at 0 144.78 0)
      (effects (font (size 1.27 1.27)) (justify left bottom) hide)
    )
    (pin "1")
    (pin "2")
    (instances
      (project "kria-k26-devboard"
        (path ""
          (reference "C143") (unit 1)
        )
      )
    )
  )

  (symbol (lib_id "kria-k26-devboard:C_100n_0402") (at 38.1 124.46 270) (unit 1)
    (in_bom yes) (on_board yes) (dnp no)
    (property "Reference" "C145" (at 38.735 125.095 90)
      (effects (font (size 1.524 1.524)) (justify left))
    )
    (property "Value" "C_100n_0402" (at 34.29 124.46 0)
      (effects (font (size 1.27 1.27) (thickness 0.15)) (justify left bottom) hide)
    )
    (property "Footprint" "kria-k26-devboard-footprints:C_0402_1005Metric" (at 43.18 129.54 0)
      (effects (font (size 1.27 1.27) (thickness 0.15)) (justify left bottom) hide)
    )
    (property "Datasheet" "https://search.murata.co.jp/Ceramy/image/img/A01X/G101/ENG/GRM155R61H104KE14-01.pdf" (at 38.1 124.46 0)
      (effects (font (size 1.27 1.27) (thickness 0.15)) (justify left bottom) hide)
    )
    (property "Manufacturer" "Murata" (at 48.26 129.54 0)
      (effects (font (size 1.27 1.27) (thickness 0.15)) (justify left bottom) hide)
    )
    (property "MPN" "GRM155R61H104KE14D" (at 45.72 129.54 0)
      (effects (font (size 1.27 1.27) (thickness 0.15)) (justify left bottom) hide)
    )
    (property "Val" "100n" (at 38.735 128.905 90)
      (effects (font (size 1.27 1.27) (thickness 0.15)) (justify left))
    )
    (property "License" "Apache-2.0" (at 15.24 144.78 0)
      (effects (font (size 1.27 1.27) (thickness 0.15)) (justify left bottom) hide)
    )
    (property "Author" "Antmicro" (at 12.7 144.78 0)
      (effects (font (size 1.27 1.27) (thickness 0.15)) (justify left bottom) hide)
    )
    (property "Voltage" "50V" (at 10.16 144.78 0)
      (effects (font (size 1.27 1.27)) (justify left bottom) hide)
    )
    (property "Dielectric" "X5R" (at 7.62 144.78 0)
      (effects (font (size 1.27 1.27)) (justify left bottom) hide)
    )
    (pin "1")
    (pin "2")
    (instances
      (project "kria-k26-devboard"
        (path ""
          (reference "C145") (unit 1)
        )
      )
    )
  )

  (symbol (lib_id "kria-k26-devboard:C_100n_0402") (at 45.72 124.46 270) (unit 1)
    (in_bom yes) (on_board yes) (dnp no)
    (property "Reference" "C147" (at 46.355 125.095 90)
      (effects (font (size 1.524 1.524)) (justify left))
    )
    (property "Value" "C_100n_0402" (at 41.91 124.46 0)
      (effects (font (size 1.27 1.27) (thickness 0.15)) (justify left bottom) hide)
    )
    (property "Footprint" "kria-k26-devboard-footprints:C_0402_1005Metric" (at 50.8 129.54 0)
      (effects (font (size 1.27 1.27) (thickness 0.15)) (justify left bottom) hide)
    )
    (property "Datasheet" "https://search.murata.co.jp/Ceramy/image/img/A01X/G101/ENG/GRM155R61H104KE14-01.pdf" (at 45.72 124.46 0)
      (effects (font (size 1.27 1.27) (thickness 0.15)) (justify left bottom) hide)
    )
    (property "Manufacturer" "Murata" (at 55.88 129.54 0)
      (effects (font (size 1.27 1.27) (thickness 0.15)) (justify left bottom) hide)
    )
    (property "MPN" "GRM155R61H104KE14D" (at 53.34 129.54 0)
      (effects (font (size 1.27 1.27) (thickness 0.15)) (justify left bottom) hide)
    )
    (property "Val" "100n" (at 46.355 128.905 90)
      (effects (font (size 1.27 1.27) (thickness 0.15)) (justify left))
    )
    (property "License" "Apache-2.0" (at 22.86 144.78 0)
      (effects (font (size 1.27 1.27) (thickness 0.15)) (justify left bottom) hide)
    )
    (property "Author" "Antmicro" (at 20.32 144.78 0)
      (effects (font (size 1.27 1.27) (thickness 0.15)) (justify left bottom) hide)
    )
    (property "Voltage" "50V" (at 17.78 144.78 0)
      (effects (font (size 1.27 1.27)) (justify left bottom) hide)
    )
    (property "Dielectric" "X5R" (at 15.24 144.78 0)
      (effects (font (size 1.27 1.27)) (justify left bottom) hide)
    )
    (pin "1")
    (pin "2")
    (instances
      (project "kria-k26-devboard"
        (path ""
          (reference "C147") (unit 1)
        )
      )
    )
  )

  (symbol (lib_id "kria-k26-devboard:C_100n_0402") (at 53.34 124.46 270) (unit 1)
    (in_bom yes) (on_board yes) (dnp no)
    (property "Reference" "C151" (at 53.975 125.095 90)
      (effects (font (size 1.524 1.524)) (justify left))
    )
    (property "Value" "C_100n_0402" (at 49.53 124.46 0)
      (effects (font (size 1.27 1.27) (thickness 0.15)) (justify left bottom) hide)
    )
    (property "Footprint" "kria-k26-devboard-footprints:C_0402_1005Metric" (at 58.42 129.54 0)
      (effects (font (size 1.27 1.27) (thickness 0.15)) (justify left bottom) hide)
    )
    (property "Datasheet" "https://search.murata.co.jp/Ceramy/image/img/A01X/G101/ENG/GRM155R61H104KE14-01.pdf" (at 53.34 124.46 0)
      (effects (font (size 1.27 1.27) (thickness 0.15)) (justify left bottom) hide)
    )
    (property "Manufacturer" "Murata" (at 63.5 129.54 0)
      (effects (font (size 1.27 1.27) (thickness 0.15)) (justify left bottom) hide)
    )
    (property "MPN" "GRM155R61H104KE14D" (at 60.96 129.54 0)
      (effects (font (size 1.27 1.27) (thickness 0.15)) (justify left bottom) hide)
    )
    (property "Val" "100n" (at 53.975 128.905 90)
      (effects (font (size 1.27 1.27) (thickness 0.15)) (justify left))
    )
    (property "License" "Apache-2.0" (at 30.48 144.78 0)
      (effects (font (size 1.27 1.27) (thickness 0.15)) (justify left bottom) hide)
    )
    (property "Author" "Antmicro" (at 27.94 144.78 0)
      (effects (font (size 1.27 1.27) (thickness 0.15)) (justify left bottom) hide)
    )
    (property "Voltage" "50V" (at 25.4 144.78 0)
      (effects (font (size 1.27 1.27)) (justify left bottom) hide)
    )
    (property "Dielectric" "X5R" (at 22.86 144.78 0)
      (effects (font (size 1.27 1.27)) (justify left bottom) hide)
    )
    (pin "1")
    (pin "2")
    (instances
      (project "kria-k26-devboard"
        (path ""
          (reference "C151") (unit 1)
        )
      )
    )
  )

  (symbol (lib_id "kria-k26-devboard:GND") (at 60.96 129.54 0) (unit 1)
    (in_bom yes) (on_board yes) (dnp no) (fields_autoplaced)
    (property "Reference" "#PWR0324" (at 60.96 135.89 0)
      (effects (font (size 1.27 1.27)) hide)
    )
    (property "Value" "GND" (at 60.96 134.62 0)
      (effects (font (size 1.27 1.27)))
    )
    (property "Footprint" "" (at 69.85 137.16 0)
      (effects (font (size 1.27 1.27) (thickness 0.15)) (justify left bottom) hide)
    )
    (property "Datasheet" "" (at 69.85 142.24 0)
      (effects (font (size 1.27 1.27) (thickness 0.15)) (justify left bottom) hide)
    )
    (property "Author" "Antmicro" (at 69.85 137.16 0)
      (effects (font (size 1.27 1.27) (thickness 0.15)) (justify left bottom) hide)
    )
    (property "License" "Apache-2.0" (at 69.85 139.7 0)
      (effects (font (size 1.27 1.27) (thickness 0.15)) (justify left bottom) hide)
    )
    (pin "1")
    (instances
      (project "kria-k26-devboard"
        (path ""
          (reference "#PWR0324") (unit 1)
        )
      )
    )
  )

  (symbol (lib_id "kria-k26-devboard:C_100n_0402") (at 22.86 104.775 270) (unit 1)
    (in_bom yes) (on_board yes) (dnp no)
    (property "Reference" "C140" (at 23.495 105.41 90)
      (effects (font (size 1.524 1.524)) (justify left))
    )
    (property "Value" "C_100n_0402" (at 19.05 104.775 0)
      (effects (font (size 1.27 1.27) (thickness 0.15)) (justify left bottom) hide)
    )
    (property "Footprint" "kria-k26-devboard-footprints:C_0402_1005Metric" (at 27.94 109.855 0)
      (effects (font (size 1.27 1.27) (thickness 0.15)) (justify left bottom) hide)
    )
    (property "Datasheet" "https://search.murata.co.jp/Ceramy/image/img/A01X/G101/ENG/GRM155R61H104KE14-01.pdf" (at 22.86 104.775 0)
      (effects (font (size 1.27 1.27) (thickness 0.15)) (justify left bottom) hide)
    )
    (property "Manufacturer" "Murata" (at 33.02 109.855 0)
      (effects (font (size 1.27 1.27) (thickness 0.15)) (justify left bottom) hide)
    )
    (property "MPN" "GRM155R61H104KE14D" (at 30.48 109.855 0)
      (effects (font (size 1.27 1.27) (thickness 0.15)) (justify left bottom) hide)
    )
    (property "Val" "100n" (at 23.495 109.22 90)
      (effects (font (size 1.27 1.27) (thickness 0.15)) (justify left))
    )
    (property "License" "Apache-2.0" (at 0 125.095 0)
      (effects (font (size 1.27 1.27) (thickness 0.15)) (justify left bottom) hide)
    )
    (property "Author" "Antmicro" (at -2.54 125.095 0)
      (effects (font (size 1.27 1.27) (thickness 0.15)) (justify left bottom) hide)
    )
    (property "Voltage" "50V" (at -5.08 125.095 0)
      (effects (font (size 1.27 1.27)) (justify left bottom) hide)
    )
    (property "Dielectric" "X5R" (at -7.62 125.095 0)
      (effects (font (size 1.27 1.27)) (justify left bottom) hide)
    )
    (pin "1")
    (pin "2")
    (instances
      (project "kria-k26-devboard"
        (path ""
          (reference "C140") (unit 1)
        )
      )
    )
  )

  (symbol (lib_id "kria-k26-devboard:C_100n_0402") (at 30.48 104.775 270) (unit 1)
    (in_bom yes) (on_board yes) (dnp no)
    (property "Reference" "C142" (at 31.115 105.4227 90)
      (effects (font (size 1.524 1.524)) (justify left))
    )
    (property "Value" "C_100n_0402" (at 26.67 104.775 0)
      (effects (font (size 1.27 1.27) (thickness 0.15)) (justify left bottom) hide)
    )
    (property "Footprint" "kria-k26-devboard-footprints:C_0402_1005Metric" (at 35.56 109.855 0)
      (effects (font (size 1.27 1.27) (thickness 0.15)) (justify left bottom) hide)
    )
    (property "Datasheet" "https://search.murata.co.jp/Ceramy/image/img/A01X/G101/ENG/GRM155R61H104KE14-01.pdf" (at 30.48 104.775 0)
      (effects (font (size 1.27 1.27) (thickness 0.15)) (justify left bottom) hide)
    )
    (property "Manufacturer" "Murata" (at 40.64 109.855 0)
      (effects (font (size 1.27 1.27) (thickness 0.15)) (justify left bottom) hide)
    )
    (property "MPN" "GRM155R61H104KE14D" (at 38.1 109.855 0)
      (effects (font (size 1.27 1.27) (thickness 0.15)) (justify left bottom) hide)
    )
    (property "Val" "100n" (at 31.115 109.2327 90)
      (effects (font (size 1.27 1.27) (thickness 0.15)) (justify left))
    )
    (property "License" "Apache-2.0" (at 7.62 125.095 0)
      (effects (font (size 1.27 1.27) (thickness 0.15)) (justify left bottom) hide)
    )
    (property "Author" "Antmicro" (at 5.08 125.095 0)
      (effects (font (size 1.27 1.27) (thickness 0.15)) (justify left bottom) hide)
    )
    (property "Voltage" "50V" (at 2.54 125.095 0)
      (effects (font (size 1.27 1.27)) (justify left bottom) hide)
    )
    (property "Dielectric" "X5R" (at 0 125.095 0)
      (effects (font (size 1.27 1.27)) (justify left bottom) hide)
    )
    (pin "1")
    (pin "2")
    (instances
      (project "kria-k26-devboard"
        (path ""
          (reference "C142") (unit 1)
        )
      )
    )
  )

  (symbol (lib_id "kria-k26-devboard:C_100n_0402") (at 38.1 104.775 270) (unit 1)
    (in_bom yes) (on_board yes) (dnp no)
    (property "Reference" "C144" (at 38.735 105.41 90)
      (effects (font (size 1.524 1.524)) (justify left))
    )
    (property "Value" "C_100n_0402" (at 34.29 104.775 0)
      (effects (font (size 1.27 1.27) (thickness 0.15)) (justify left bottom) hide)
    )
    (property "Footprint" "kria-k26-devboard-footprints:C_0402_1005Metric" (at 43.18 109.855 0)
      (effects (font (size 1.27 1.27) (thickness 0.15)) (justify left bottom) hide)
    )
    (property "Datasheet" "https://search.murata.co.jp/Ceramy/image/img/A01X/G101/ENG/GRM155R61H104KE14-01.pdf" (at 38.1 104.775 0)
      (effects (font (size 1.27 1.27) (thickness 0.15)) (justify left bottom) hide)
    )
    (property "Manufacturer" "Murata" (at 48.26 109.855 0)
      (effects (font (size 1.27 1.27) (thickness 0.15)) (justify left bottom) hide)
    )
    (property "MPN" "GRM155R61H104KE14D" (at 45.72 109.855 0)
      (effects (font (size 1.27 1.27) (thickness 0.15)) (justify left bottom) hide)
    )
    (property "Val" "100n" (at 38.735 109.22 90)
      (effects (font (size 1.27 1.27) (thickness 0.15)) (justify left))
    )
    (property "License" "Apache-2.0" (at 15.24 125.095 0)
      (effects (font (size 1.27 1.27) (thickness 0.15)) (justify left bottom) hide)
    )
    (property "Author" "Antmicro" (at 12.7 125.095 0)
      (effects (font (size 1.27 1.27) (thickness 0.15)) (justify left bottom) hide)
    )
    (property "Voltage" "50V" (at 10.16 125.095 0)
      (effects (font (size 1.27 1.27)) (justify left bottom) hide)
    )
    (property "Dielectric" "X5R" (at 7.62 125.095 0)
      (effects (font (size 1.27 1.27)) (justify left bottom) hide)
    )
    (pin "1")
    (pin "2")
    (instances
      (project "kria-k26-devboard"
        (path ""
          (reference "C144") (unit 1)
        )
      )
    )
  )

  (symbol (lib_id "kria-k26-devboard:C_100n_0402") (at 45.72 104.775 270) (unit 1)
    (in_bom yes) (on_board yes) (dnp no)
    (property "Reference" "C146" (at 46.355 105.4227 90)
      (effects (font (size 1.524 1.524)) (justify left))
    )
    (property "Value" "C_100n_0402" (at 41.91 104.775 0)
      (effects (font (size 1.27 1.27) (thickness 0.15)) (justify left bottom) hide)
    )
    (property "Footprint" "kria-k26-devboard-footprints:C_0402_1005Metric" (at 50.8 109.855 0)
      (effects (font (size 1.27 1.27) (thickness 0.15)) (justify left bottom) hide)
    )
    (property "Datasheet" "https://search.murata.co.jp/Ceramy/image/img/A01X/G101/ENG/GRM155R61H104KE14-01.pdf" (at 45.72 104.775 0)
      (effects (font (size 1.27 1.27) (thickness 0.15)) (justify left bottom) hide)
    )
    (property "Manufacturer" "Murata" (at 55.88 109.855 0)
      (effects (font (size 1.27 1.27) (thickness 0.15)) (justify left bottom) hide)
    )
    (property "MPN" "GRM155R61H104KE14D" (at 53.34 109.855 0)
      (effects (font (size 1.27 1.27) (thickness 0.15)) (justify left bottom) hide)
    )
    (property "Val" "100n" (at 46.355 109.2327 90)
      (effects (font (size 1.27 1.27) (thickness 0.15)) (justify left))
    )
    (property "License" "Apache-2.0" (at 22.86 125.095 0)
      (effects (font (size 1.27 1.27) (thickness 0.15)) (justify left bottom) hide)
    )
    (property "Author" "Antmicro" (at 20.32 125.095 0)
      (effects (font (size 1.27 1.27) (thickness 0.15)) (justify left bottom) hide)
    )
    (property "Voltage" "50V" (at 17.78 125.095 0)
      (effects (font (size 1.27 1.27)) (justify left bottom) hide)
    )
    (property "Dielectric" "X5R" (at 15.24 125.095 0)
      (effects (font (size 1.27 1.27)) (justify left bottom) hide)
    )
    (pin "1")
    (pin "2")
    (instances
      (project "kria-k26-devboard"
        (path ""
          (reference "C146") (unit 1)
        )
      )
    )
  )

  (symbol (lib_id "kria-k26-devboard:GND") (at 53.34 109.855 0) (unit 1)
    (in_bom yes) (on_board yes) (dnp no) (fields_autoplaced)
    (property "Reference" "#PWR0323" (at 53.34 116.205 0)
      (effects (font (size 1.27 1.27)) hide)
    )
    (property "Value" "GND" (at 53.34 114.935 0)
      (effects (font (size 1.27 1.27)))
    )
    (property "Footprint" "" (at 62.23 117.475 0)
      (effects (font (size 1.27 1.27) (thickness 0.15)) (justify left bottom) hide)
    )
    (property "Datasheet" "" (at 62.23 122.555 0)
      (effects (font (size 1.27 1.27) (thickness 0.15)) (justify left bottom) hide)
    )
    (property "Author" "Antmicro" (at 62.23 117.475 0)
      (effects (font (size 1.27 1.27) (thickness 0.15)) (justify left bottom) hide)
    )
    (property "License" "Apache-2.0" (at 62.23 120.015 0)
      (effects (font (size 1.27 1.27) (thickness 0.15)) (justify left bottom) hide)
    )
    (pin "1")
    (instances
      (project "kria-k26-devboard"
        (path ""
          (reference "#PWR0323") (unit 1)
        )
      )
    )
  )

  (symbol (lib_id "kria-k26-devboard:C_4u7_0402") (at 53.34 109.855 90) (unit 1)
    (in_bom yes) (on_board yes) (dnp no)
    (property "Reference" "C150" (at 53.975 105.41 90)
      (effects (font (size 1.524 1.524)) (justify right))
    )
    (property "Value" "C_4u7_0402" (at 57.15 109.855 0)
      (effects (font (size 1.27 1.27) (thickness 0.15)) (justify left bottom) hide)
    )
    (property "Footprint" "kria-k26-devboard-footprints:C_0402_1005Metric" (at 48.26 104.775 0)
      (effects (font (size 1.27 1.27) (thickness 0.15)) (justify left bottom) hide)
    )
    (property "Datasheet" " " (at 53.34 109.855 0)
      (effects (font (size 1.27 1.27) (thickness 0.15)) (justify left bottom) hide)
    )
    (property "Manufacturer" "Murata" (at 43.18 104.775 0)
      (effects (font (size 1.27 1.27) (thickness 0.15)) (justify left bottom) hide)
    )
    (property "MPN" "GRM155R61A475MEAAD" (at 45.72 104.775 0)
      (effects (font (size 1.27 1.27) (thickness 0.15)) (justify left bottom) hide)
    )
    (property "Val" "4u7" (at 53.975 109.22 90)
      (effects (font (size 1.27 1.27) (thickness 0.15)) (justify right))
    )
    (property "License" "Apache-2.0" (at 76.2 89.535 0)
      (effects (font (size 1.27 1.27) (thickness 0.15)) (justify left bottom) hide)
    )
    (property "Author" "Antmicro" (at 78.74 89.535 0)
      (effects (font (size 1.27 1.27) (thickness 0.15)) (justify left bottom) hide)
    )
    (property "Voltage" "" (at 81.28 89.535 0)
      (effects (font (size 1.27 1.27)) (justify left bottom) hide)
    )
    (property "Dielectric" "" (at 83.82 89.535 0)
      (effects (font (size 1.27 1.27)) (justify left bottom) hide)
    )
    (pin "1")
    (pin "2")
    (instances
      (project "kria-k26-devboard"
        (path ""
          (reference "C150") (unit 1)
        )
      )
    )
  )

  (symbol (lib_id "kria-k26-devboard:FB_120Z_1.3A_Murata-BLM15PD_0402") (at 36.703 153.67 0) (unit 1)
    (in_bom yes) (on_board yes) (dnp no)
    (property "Reference" "FB5" (at 39.243 147.32 0)
      (effects (font (size 1.524 1.524)))
    )
    (property "Value" "FB_120Z_1.3A_0402" (at 39.2049 149.86 0)
      (effects (font (size 1.27 1.27) (thickness 0.15)))
    )
    (property "Footprint" "kria-k26-devboard-footprints:FB_0402_1005Metric" (at 41.783 148.59 0)
      (effects (font (size 1.27 1.27) (thickness 0.15)) (justify left bottom) hide)
    )
    (property "Datasheet" "https://www.murata.com/en-us/products/productdata/8796740059166/ENFA0018.pdf" (at 41.783 146.05 0)
      (effects (font (size 1.27 1.27) (thickness 0.15)) (justify left bottom) hide)
    )
    (property "MPN" "BLM15PD121SN1D" (at 41.783 140.97 0)
      (effects (font (size 1.27 1.27) (thickness 0.15)) (justify left bottom) hide)
    )
    (property "Manufacturer" "Murata" (at 41.783 125.73 0)
      (effects (font (size 1.27 1.27) (thickness 0.15)) (justify left bottom) hide)
    )
    (property "Author" "Antmicro" (at 50.673 168.91 0)
      (effects (font (size 1.27 1.27) (thickness 0.15)) (justify left bottom) hide)
    )
    (property "License" "Apache-2.0" (at 50.673 171.45 0)
      (effects (font (size 1.27 1.27) (thickness 0.15)) (justify left bottom) hide)
    )
    (pin "1")
    (pin "2")
    (instances
      (project "kria-k26-devboard"
        (path ""
          (reference "FB5") (unit 1)
        )
      )
    )
  )

  (symbol (lib_id "kria-k26-devboard:C_100n_0402") (at 51.308 156.21 270) (unit 1)
    (in_bom yes) (on_board yes) (dnp no) (fields_autoplaced)
    (property "Reference" "C152" (at 53.848 157.4863 90)
      (effects (font (size 1.524 1.524)) (justify left))
    )
    (property "Value" "C_100n_0402" (at 47.498 156.21 0)
      (effects (font (size 1.27 1.27) (thickness 0.15)) (justify left bottom) hide)
    )
    (property "Footprint" "kria-k26-devboard-footprints:C_0402_1005Metric" (at 56.388 161.29 0)
      (effects (font (size 1.27 1.27) (thickness 0.15)) (justify left bottom) hide)
    )
    (property "Datasheet" "https://search.murata.co.jp/Ceramy/image/img/A01X/G101/ENG/GRM155R61H104KE14-01.pdf" (at 51.308 156.21 0)
      (effects (font (size 1.27 1.27) (thickness 0.15)) (justify left bottom) hide)
    )
    (property "Manufacturer" "Murata" (at 61.468 161.29 0)
      (effects (font (size 1.27 1.27) (thickness 0.15)) (justify left bottom) hide)
    )
    (property "MPN" "GRM155R61H104KE14D" (at 58.928 161.29 0)
      (effects (font (size 1.27 1.27) (thickness 0.15)) (justify left bottom) hide)
    )
    (property "Val" "100n" (at 53.848 160.6612 90)
      (effects (font (size 1.27 1.27) (thickness 0.15)) (justify left))
    )
    (property "License" "Apache-2.0" (at 28.448 176.53 0)
      (effects (font (size 1.27 1.27) (thickness 0.15)) (justify left bottom) hide)
    )
    (property "Author" "Antmicro" (at 25.908 176.53 0)
      (effects (font (size 1.27 1.27) (thickness 0.15)) (justify left bottom) hide)
    )
    (property "Voltage" "50V" (at 23.368 176.53 0)
      (effects (font (size 1.27 1.27)) (justify left bottom) hide)
    )
    (property "Dielectric" "X5R" (at 20.828 176.53 0)
      (effects (font (size 1.27 1.27)) (justify left bottom) hide)
    )
    (pin "1")
    (pin "2")
    (instances
      (project "kria-k26-devboard"
        (path ""
          (reference "C152") (unit 1)
        )
      )
    )
  )

  (symbol (lib_id "kria-k26-devboard:GND") (at 51.308 161.29 0) (unit 1)
    (in_bom yes) (on_board yes) (dnp no) (fields_autoplaced)
    (property "Reference" "#PWR0325" (at 51.308 167.64 0)
      (effects (font (size 1.27 1.27)) hide)
    )
    (property "Value" "GND" (at 51.308 166.37 0)
      (effects (font (size 1.27 1.27)))
    )
    (property "Footprint" "" (at 60.198 168.91 0)
      (effects (font (size 1.27 1.27) (thickness 0.15)) (justify left bottom) hide)
    )
    (property "Datasheet" "" (at 60.198 173.99 0)
      (effects (font (size 1.27 1.27) (thickness 0.15)) (justify left bottom) hide)
    )
    (property "Author" "Antmicro" (at 60.198 168.91 0)
      (effects (font (size 1.27 1.27) (thickness 0.15)) (justify left bottom) hide)
    )
    (property "License" "Apache-2.0" (at 60.198 171.45 0)
      (effects (font (size 1.27 1.27) (thickness 0.15)) (justify left bottom) hide)
    )
    (pin "1")
    (instances
      (project "kria-k26-devboard"
        (path ""
          (reference "#PWR0325") (unit 1)
        )
      )
    )
  )

  (symbol (lib_id "kria-k26-devboard:FB_120Z_1.3A_Murata-BLM15PD_0402") (at 36.068 177.8 0) (unit 1)
    (in_bom yes) (on_board yes) (dnp no)
    (property "Reference" "FB3" (at 38.608 171.45 0)
      (effects (font (size 1.524 1.524)))
    )
    (property "Value" "FB_120Z_1.3A_0402" (at 38.5699 173.99 0)
      (effects (font (size 1.27 1.27) (thickness 0.15)))
    )
    (property "Footprint" "kria-k26-devboard-footprints:FB_0402_1005Metric" (at 41.148 172.72 0)
      (effects (font (size 1.27 1.27) (thickness 0.15)) (justify left bottom) hide)
    )
    (property "Datasheet" "https://www.murata.com/en-us/products/productdata/8796740059166/ENFA0018.pdf" (at 41.148 170.18 0)
      (effects (font (size 1.27 1.27) (thickness 0.15)) (justify left bottom) hide)
    )
    (property "MPN" "BLM15PD121SN1D" (at 41.148 165.1 0)
      (effects (font (size 1.27 1.27) (thickness 0.15)) (justify left bottom) hide)
    )
    (property "Manufacturer" "Murata" (at 41.148 149.86 0)
      (effects (font (size 1.27 1.27) (thickness 0.15)) (justify left bottom) hide)
    )
    (property "Author" "Antmicro" (at 50.038 193.04 0)
      (effects (font (size 1.27 1.27) (thickness 0.15)) (justify left bottom) hide)
    )
    (property "License" "Apache-2.0" (at 50.038 195.58 0)
      (effects (font (size 1.27 1.27) (thickness 0.15)) (justify left bottom) hide)
    )
    (pin "1")
    (pin "2")
    (instances
      (project "kria-k26-devboard"
        (path ""
          (reference "FB3") (unit 1)
        )
      )
    )
  )

  (symbol (lib_id "kria-k26-devboard:C_100n_0402") (at 51.308 180.34 270) (unit 1)
    (in_bom yes) (on_board yes) (dnp no) (fields_autoplaced)
    (property "Reference" "C148" (at 53.848 181.6163 90)
      (effects (font (size 1.524 1.524)) (justify left))
    )
    (property "Value" "C_100n_0402" (at 47.498 180.34 0)
      (effects (font (size 1.27 1.27) (thickness 0.15)) (justify left bottom) hide)
    )
    (property "Footprint" "kria-k26-devboard-footprints:C_0402_1005Metric" (at 56.388 185.42 0)
      (effects (font (size 1.27 1.27) (thickness 0.15)) (justify left bottom) hide)
    )
    (property "Datasheet" "https://search.murata.co.jp/Ceramy/image/img/A01X/G101/ENG/GRM155R61H104KE14-01.pdf" (at 51.308 180.34 0)
      (effects (font (size 1.27 1.27) (thickness 0.15)) (justify left bottom) hide)
    )
    (property "Manufacturer" "Murata" (at 61.468 185.42 0)
      (effects (font (size 1.27 1.27) (thickness 0.15)) (justify left bottom) hide)
    )
    (property "MPN" "GRM155R61H104KE14D" (at 58.928 185.42 0)
      (effects (font (size 1.27 1.27) (thickness 0.15)) (justify left bottom) hide)
    )
    (property "Val" "100n" (at 53.848 184.7912 90)
      (effects (font (size 1.27 1.27) (thickness 0.15)) (justify left))
    )
    (property "License" "Apache-2.0" (at 28.448 200.66 0)
      (effects (font (size 1.27 1.27) (thickness 0.15)) (justify left bottom) hide)
    )
    (property "Author" "Antmicro" (at 25.908 200.66 0)
      (effects (font (size 1.27 1.27) (thickness 0.15)) (justify left bottom) hide)
    )
    (property "Voltage" "50V" (at 23.368 200.66 0)
      (effects (font (size 1.27 1.27)) (justify left bottom) hide)
    )
    (property "Dielectric" "X5R" (at 20.828 200.66 0)
      (effects (font (size 1.27 1.27)) (justify left bottom) hide)
    )
    (pin "1")
    (pin "2")
    (instances
      (project "kria-k26-devboard"
        (path ""
          (reference "C148") (unit 1)
        )
      )
    )
  )

  (symbol (lib_id "kria-k26-devboard:GND") (at 51.308 185.42 0) (unit 1)
    (in_bom yes) (on_board yes) (dnp no) (fields_autoplaced)
    (property "Reference" "#PWR0321" (at 51.308 191.77 0)
      (effects (font (size 1.27 1.27)) hide)
    )
    (property "Value" "GND" (at 51.308 190.5 0)
      (effects (font (size 1.27 1.27)))
    )
    (property "Footprint" "" (at 60.198 193.04 0)
      (effects (font (size 1.27 1.27) (thickness 0.15)) (justify left bottom) hide)
    )
    (property "Datasheet" "" (at 60.198 198.12 0)
      (effects (font (size 1.27 1.27) (thickness 0.15)) (justify left bottom) hide)
    )
    (property "Author" "Antmicro" (at 60.198 193.04 0)
      (effects (font (size 1.27 1.27) (thickness 0.15)) (justify left bottom) hide)
    )
    (property "License" "Apache-2.0" (at 60.198 195.58 0)
      (effects (font (size 1.27 1.27) (thickness 0.15)) (justify left bottom) hide)
    )
    (pin "1")
    (instances
      (project "kria-k26-devboard"
        (path ""
          (reference "#PWR0321") (unit 1)
        )
      )
    )
  )

  (symbol (lib_id "kria-k26-devboard:FB_120Z_1.3A_Murata-BLM15PD_0402") (at 36.703 203.2 0) (unit 1)
    (in_bom yes) (on_board yes) (dnp no)
    (property "Reference" "FB4" (at 39.243 196.85 0)
      (effects (font (size 1.524 1.524)))
    )
    (property "Value" "FB_120Z_1.3A_0402" (at 39.2049 199.39 0)
      (effects (font (size 1.27 1.27) (thickness 0.15)))
    )
    (property "Footprint" "kria-k26-devboard-footprints:FB_0402_1005Metric" (at 41.783 198.12 0)
      (effects (font (size 1.27 1.27) (thickness 0.15)) (justify left bottom) hide)
    )
    (property "Datasheet" "https://www.murata.com/en-us/products/productdata/8796740059166/ENFA0018.pdf" (at 41.783 195.58 0)
      (effects (font (size 1.27 1.27) (thickness 0.15)) (justify left bottom) hide)
    )
    (property "MPN" "BLM15PD121SN1D" (at 41.783 190.5 0)
      (effects (font (size 1.27 1.27) (thickness 0.15)) (justify left bottom) hide)
    )
    (property "Manufacturer" "Murata" (at 41.783 175.26 0)
      (effects (font (size 1.27 1.27) (thickness 0.15)) (justify left bottom) hide)
    )
    (property "Author" "Antmicro" (at 50.673 218.44 0)
      (effects (font (size 1.27 1.27) (thickness 0.15)) (justify left bottom) hide)
    )
    (property "License" "Apache-2.0" (at 50.673 220.98 0)
      (effects (font (size 1.27 1.27) (thickness 0.15)) (justify left bottom) hide)
    )
    (pin "1")
    (pin "2")
    (instances
      (project "kria-k26-devboard"
        (path ""
          (reference "FB4") (unit 1)
        )
      )
    )
  )

  (symbol (lib_id "kria-k26-devboard:C_100n_0402") (at 51.308 205.74 270) (unit 1)
    (in_bom yes) (on_board yes) (dnp no) (fields_autoplaced)
    (property "Reference" "C149" (at 53.848 207.0163 90)
      (effects (font (size 1.524 1.524)) (justify left))
    )
    (property "Value" "C_100n_0402" (at 47.498 205.74 0)
      (effects (font (size 1.27 1.27) (thickness 0.15)) (justify left bottom) hide)
    )
    (property "Footprint" "kria-k26-devboard-footprints:C_0402_1005Metric" (at 56.388 210.82 0)
      (effects (font (size 1.27 1.27) (thickness 0.15)) (justify left bottom) hide)
    )
    (property "Datasheet" "https://search.murata.co.jp/Ceramy/image/img/A01X/G101/ENG/GRM155R61H104KE14-01.pdf" (at 51.308 205.74 0)
      (effects (font (size 1.27 1.27) (thickness 0.15)) (justify left bottom) hide)
    )
    (property "Manufacturer" "Murata" (at 61.468 210.82 0)
      (effects (font (size 1.27 1.27) (thickness 0.15)) (justify left bottom) hide)
    )
    (property "MPN" "GRM155R61H104KE14D" (at 58.928 210.82 0)
      (effects (font (size 1.27 1.27) (thickness 0.15)) (justify left bottom) hide)
    )
    (property "Val" "100n" (at 53.848 210.1912 90)
      (effects (font (size 1.27 1.27) (thickness 0.15)) (justify left))
    )
    (property "License" "Apache-2.0" (at 28.448 226.06 0)
      (effects (font (size 1.27 1.27) (thickness 0.15)) (justify left bottom) hide)
    )
    (property "Author" "Antmicro" (at 25.908 226.06 0)
      (effects (font (size 1.27 1.27) (thickness 0.15)) (justify left bottom) hide)
    )
    (property "Voltage" "50V" (at 23.368 226.06 0)
      (effects (font (size 1.27 1.27)) (justify left bottom) hide)
    )
    (property "Dielectric" "X5R" (at 20.828 226.06 0)
      (effects (font (size 1.27 1.27)) (justify left bottom) hide)
    )
    (pin "1")
    (pin "2")
    (instances
      (project "kria-k26-devboard"
        (path ""
          (reference "C149") (unit 1)
        )
      )
    )
  )

  (symbol (lib_id "kria-k26-devboard:GND") (at 51.308 210.82 0) (unit 1)
    (in_bom yes) (on_board yes) (dnp no) (fields_autoplaced)
    (property "Reference" "#PWR0322" (at 51.308 217.17 0)
      (effects (font (size 1.27 1.27)) hide)
    )
    (property "Value" "GND" (at 51.308 215.9 0)
      (effects (font (size 1.27 1.27)))
    )
    (property "Footprint" "" (at 60.198 218.44 0)
      (effects (font (size 1.27 1.27) (thickness 0.15)) (justify left bottom) hide)
    )
    (property "Datasheet" "" (at 60.198 223.52 0)
      (effects (font (size 1.27 1.27) (thickness 0.15)) (justify left bottom) hide)
    )
    (property "Author" "Antmicro" (at 60.198 218.44 0)
      (effects (font (size 1.27 1.27) (thickness 0.15)) (justify left bottom) hide)
    )
    (property "License" "Apache-2.0" (at 60.198 220.98 0)
      (effects (font (size 1.27 1.27) (thickness 0.15)) (justify left bottom) hide)
    )
    (pin "1")
    (instances
      (project "kria-k26-devboard"
        (path ""
          (reference "#PWR0322") (unit 1)
        )
      )
    )
  )

  (symbol (lib_id "kria-k26-devboard:DTC014T_SOT-416") (at 226.06 49.53 0) (unit 1)
    (in_bom yes) (on_board yes) (dnp no) (fields_autoplaced)
    (property "Reference" "Q11" (at 236.22 48.2599 0)
      (effects (font (size 1.27 1.27)) (justify left))
    )
    (property "Value" "DTC014T_SOT-416" (at 236.22 50.7999 0)
      (effects (font (size 1.27 1.27) (thickness 0.15)) (justify left) hide)
    )
    (property "Footprint" "kria-k26-devboard-footprints:SOT-416" (at 231.14 57.15 0)
      (effects (font (size 1.27 1.27) (thickness 0.15)) (justify left bottom) hide)
    )
    (property "Datasheet" "https://www.rohm.com/datasheet?p=DTC014TEB&dist=Mouser&media=referral&source=mouser.com&campaign=Mouser" (at 226.06 49.53 0)
      (effects (font (size 1.27 1.27) (thickness 0.15)) (justify left bottom) hide)
    )
    (property "Manufacturer" "ROHM Semiconductor" (at 241.3 52.07 0)
      (effects (font (size 1.27 1.27) (thickness 0.15)) (justify left bottom) hide)
    )
    (property "MPN" "DTC014TEBTL" (at 236.22 50.7999 0)
      (effects (font (size 1.27 1.27) (thickness 0.15)) (justify left))
    )
    (property "Author" "Antmicro" (at 251.46 69.85 0)
      (effects (font (size 1.27 1.27) (thickness 0.15)) (justify left bottom) hide)
    )
    (property "License" "Apache-2.0" (at 251.46 72.39 0)
      (effects (font (size 1.27 1.27) (thickness 0.15)) (justify left bottom) hide)
    )
    (pin "1")
    (pin "2")
    (pin "3")
    (instances
      (project "kria-k26-devboard"
        (path ""
          (reference "Q11") (unit 1)
        )
      )
    )
  )

  (symbol (lib_id "kria-k26-devboard:TP_0.75mm_SMD") (at 168.275 51.435 90) (unit 1)
    (in_bom yes) (on_board yes) (dnp no) (fields_autoplaced)
    (property "Reference" "TP29" (at 170.18 48.2599 90)
      (effects (font (size 1.27 1.27)) (justify right))
    )
    (property "Value" "TP_0.75mm_SMD" (at 170.815 51.435 0)
      (effects (font (size 1.27 1.27) (thickness 0.15)) (justify left bottom) hide)
    )
    (property "Footprint" "kria-k26-devboard-footprints:TP_SMD_0.75mm" (at 163.195 46.355 0)
      (effects (font (size 1.27 1.27) (thickness 0.15)) (justify left bottom) hide)
    )
    (property "Datasheet" "" (at 160.655 46.355 0)
      (effects (font (size 1.27 1.27) (thickness 0.15)) (justify left bottom) hide)
    )
    (property "MPN" "" (at 168.275 51.435 0)
      (effects (font (size 1.27 1.27) (thickness 0.15)) (justify left bottom) hide)
    )
    (property "Manufacturer" "" (at 168.275 51.435 0)
      (effects (font (size 1.27 1.27) (thickness 0.15)) (justify left bottom) hide)
    )
    (property "Author" "Antmicro" (at 183.515 36.195 0)
      (effects (font (size 1.27 1.27) (thickness 0.15)) (justify left bottom) hide)
    )
    (property "License" "Apache-2.0" (at 186.055 36.195 0)
      (effects (font (size 1.27 1.27) (thickness 0.15)) (justify left bottom) hide)
    )
    (pin "1")
    (instances
      (project "kria-k26-devboard"
        (path ""
          (reference "TP29") (unit 1)
        )
      )
    )
  )

  (symbol (lib_id "kria-k26-devboard:TP_0.75mm_SMD") (at 204.47 59.69 90) (unit 1)
    (in_bom yes) (on_board yes) (dnp no) (fields_autoplaced)
    (property "Reference" "TP30" (at 204.47 52.705 90)
      (effects (font (size 1.27 1.27)))
    )
    (property "Value" "TP_0.75mm_SMD" (at 207.01 59.69 0)
      (effects (font (size 1.27 1.27) (thickness 0.15)) (justify left bottom) hide)
    )
    (property "Footprint" "kria-k26-devboard-footprints:TP_SMD_0.75mm" (at 199.39 54.61 0)
      (effects (font (size 1.27 1.27) (thickness 0.15)) (justify left bottom) hide)
    )
    (property "Datasheet" "" (at 196.85 54.61 0)
      (effects (font (size 1.27 1.27) (thickness 0.15)) (justify left bottom) hide)
    )
    (property "MPN" "" (at 204.47 59.69 0)
      (effects (font (size 1.27 1.27) (thickness 0.15)) (justify left bottom) hide)
    )
    (property "Manufacturer" "" (at 204.47 59.69 0)
      (effects (font (size 1.27 1.27) (thickness 0.15)) (justify left bottom) hide)
    )
    (property "Author" "Antmicro" (at 219.71 44.45 0)
      (effects (font (size 1.27 1.27) (thickness 0.15)) (justify left bottom) hide)
    )
    (property "License" "Apache-2.0" (at 222.25 44.45 0)
      (effects (font (size 1.27 1.27) (thickness 0.15)) (justify left bottom) hide)
    )
    (pin "1")
    (instances
      (project "kria-k26-devboard"
        (path ""
          (reference "TP30") (unit 1)
        )
      )
    )
  )

  (symbol (lib_id "kria-k26-devboard:TP_0.75mm_SMD") (at 220.98 48.26 90) (unit 1)
    (in_bom yes) (on_board yes) (dnp no) (fields_autoplaced)
    (property "Reference" "TP31" (at 223.52 45.0849 90)
      (effects (font (size 1.27 1.27)) (justify right))
    )
    (property "Value" "TP_0.75mm_SMD" (at 223.52 48.26 0)
      (effects (font (size 1.27 1.27) (thickness 0.15)) (justify left bottom) hide)
    )
    (property "Footprint" "kria-k26-devboard-footprints:TP_SMD_0.75mm" (at 215.9 43.18 0)
      (effects (font (size 1.27 1.27) (thickness 0.15)) (justify left bottom) hide)
    )
    (property "Datasheet" "" (at 213.36 43.18 0)
      (effects (font (size 1.27 1.27) (thickness 0.15)) (justify left bottom) hide)
    )
    (property "MPN" "" (at 220.98 48.26 0)
      (effects (font (size 1.27 1.27) (thickness 0.15)) (justify left bottom) hide)
    )
    (property "Manufacturer" "" (at 220.98 48.26 0)
      (effects (font (size 1.27 1.27) (thickness 0.15)) (justify left bottom) hide)
    )
    (property "Author" "Antmicro" (at 236.22 33.02 0)
      (effects (font (size 1.27 1.27) (thickness 0.15)) (justify left bottom) hide)
    )
    (property "License" "Apache-2.0" (at 238.76 33.02 0)
      (effects (font (size 1.27 1.27) (thickness 0.15)) (justify left bottom) hide)
    )
    (pin "1")
    (instances
      (project "kria-k26-devboard"
        (path ""
          (reference "TP31") (unit 1)
        )
      )
    )
  )

  (symbol (lib_id "kria-k26-devboard:TP_0.75mm_SMD") (at 241.3 40.64 90) (unit 1)
    (in_bom yes) (on_board yes) (dnp no) (fields_autoplaced)
    (property "Reference" "TP32" (at 243.84 37.4649 90)
      (effects (font (size 1.27 1.27)) (justify right))
    )
    (property "Value" "TP_0.75mm_SMD" (at 243.84 40.64 0)
      (effects (font (size 1.27 1.27) (thickness 0.15)) (justify left bottom) hide)
    )
    (property "Footprint" "kria-k26-devboard-footprints:TP_SMD_0.75mm" (at 236.22 35.56 0)
      (effects (font (size 1.27 1.27) (thickness 0.15)) (justify left bottom) hide)
    )
    (property "Datasheet" "" (at 233.68 35.56 0)
      (effects (font (size 1.27 1.27) (thickness 0.15)) (justify left bottom) hide)
    )
    (property "MPN" "" (at 241.3 40.64 0)
      (effects (font (size 1.27 1.27) (thickness 0.15)) (justify left bottom) hide)
    )
    (property "Manufacturer" "" (at 241.3 40.64 0)
      (effects (font (size 1.27 1.27) (thickness 0.15)) (justify left bottom) hide)
    )
    (property "Author" "Antmicro" (at 256.54 25.4 0)
      (effects (font (size 1.27 1.27) (thickness 0.15)) (justify left bottom) hide)
    )
    (property "License" "Apache-2.0" (at 259.08 25.4 0)
      (effects (font (size 1.27 1.27) (thickness 0.15)) (justify left bottom) hide)
    )
    (pin "1")
    (instances
      (project "kria-k26-devboard"
        (path ""
          (reference "TP32") (unit 1)
        )
      )
    )
  )

  (symbol (lib_id "kria-k26-devboard:DTC014T_SOT-416") (at 313.69 228.6 0) (unit 1)
    (in_bom yes) (on_board yes) (dnp no) (fields_autoplaced)
    (property "Reference" "Q12" (at 323.85 227.3299 0)
      (effects (font (size 1.27 1.27)) (justify left))
    )
    (property "Value" "DTC014T_SOT-416" (at 323.85 229.8699 0)
      (effects (font (size 1.27 1.27) (thickness 0.15)) (justify left) hide)
    )
    (property "Footprint" "kria-k26-devboard-footprints:SOT-416" (at 318.77 236.22 0)
      (effects (font (size 1.27 1.27) (thickness 0.15)) (justify left bottom) hide)
    )
    (property "Datasheet" "https://www.rohm.com/datasheet?p=DTC014TEB&dist=Mouser&media=referral&source=mouser.com&campaign=Mouser" (at 313.69 228.6 0)
      (effects (font (size 1.27 1.27) (thickness 0.15)) (justify left bottom) hide)
    )
    (property "Manufacturer" "ROHM Semiconductor" (at 328.93 231.14 0)
      (effects (font (size 1.27 1.27) (thickness 0.15)) (justify left bottom) hide)
    )
    (property "MPN" "DTC014TEBTL" (at 323.85 229.8699 0)
      (effects (font (size 1.27 1.27) (thickness 0.15)) (justify left))
    )
    (property "Author" "Antmicro" (at 339.09 248.92 0)
      (effects (font (size 1.27 1.27) (thickness 0.15)) (justify left bottom) hide)
    )
    (property "License" "Apache-2.0" (at 339.09 251.46 0)
      (effects (font (size 1.27 1.27) (thickness 0.15)) (justify left bottom) hide)
    )
    (pin "1")
    (pin "2")
    (pin "3")
    (instances
      (project "kria-k26-devboard"
        (path ""
          (reference "Q12") (unit 1)
        )
      )
    )
  )

  (symbol (lib_id "kria-k26-devboard:74AVC4T245_UQFN") (at 309.88 50.8 0) (unit 1)
    (in_bom yes) (on_board yes) (dnp no)
    (property "Reference" "U42" (at 319.405 41.275 0)
      (effects (font (size 1.27 1.27)))
    )
    (property "Value" "74AVC4T245_UQFN" (at 324.5994 77.47 0)
      (effects (font (size 1.27 1.27) (thickness 0.15)) (justify left bottom) hide)
    )
    (property "Footprint" "kria-k26-devboard-footprints:UQFN-16-1.8x2.6mm_P0.4mm_Texas_RSV0016A" (at 330.2 69.85 0)
      (effects (font (size 1.27 1.27) (thickness 0.15)) (justify left bottom) hide)
    )
    (property "Datasheet" "https://www.ti.com/lit/ds/symlink/sn74avc4t245.pdf" (at 308.61 57.15 0)
      (effects (font (size 1.27 1.27) (thickness 0.15)) (justify left bottom) hide)
    )
    (property "MPN" "74AVC4T245RSVRG4" (at 319.405 43.815 0)
      (effects (font (size 1.27 1.27) (thickness 0.15)))
    )
    (property "Manufacturer" "Texas Instruments" (at 320.04 64.77 0)
      (effects (font (size 1.27 1.27) (thickness 0.15)) (justify left bottom) hide)
    )
    (property "Author" "Antmicro" (at 347.98 71.12 0)
      (effects (font (size 1.27 1.27) (thickness 0.15)) (justify left bottom) hide)
    )
    (property "License" "Apache-2.0" (at 347.98 73.66 0)
      (effects (font (size 1.27 1.27) (thickness 0.15)) (justify left bottom) hide)
    )
    (pin "1")
    (pin "10")
    (pin "11")
    (pin "12")
    (pin "13")
    (pin "14")
    (pin "15")
    (pin "16")
    (pin "2")
    (pin "3")
    (pin "4")
    (pin "5")
    (pin "6")
    (pin "7")
    (pin "8")
    (pin "9")
    (instances
      (project "kria-k26-devboard"
        (path ""
          (reference "U42") (unit 1)
        )
      )
    )
  )

  (symbol (lib_id "kria-k26-devboard:74AVC4T245_UQFN") (at 309.88 89.535 0) (unit 1)
    (in_bom yes) (on_board yes) (dnp no)
    (property "Reference" "U43" (at 319.405 80.01 0)
      (effects (font (size 1.27 1.27)))
    )
    (property "Value" "74AVC4T245_UQFN" (at 324.5994 116.205 0)
      (effects (font (size 1.27 1.27) (thickness 0.15)) (justify left bottom) hide)
    )
    (property "Footprint" "kria-k26-devboard-footprints:UQFN-16-1.8x2.6mm_P0.4mm_Texas_RSV0016A" (at 330.2 108.585 0)
      (effects (font (size 1.27 1.27) (thickness 0.15)) (justify left bottom) hide)
    )
    (property "Datasheet" "https://www.ti.com/lit/ds/symlink/sn74avc4t245.pdf" (at 308.61 95.885 0)
      (effects (font (size 1.27 1.27) (thickness 0.15)) (justify left bottom) hide)
    )
    (property "MPN" "74AVC4T245RSVRG4" (at 319.405 82.55 0)
      (effects (font (size 1.27 1.27) (thickness 0.15)))
    )
    (property "Manufacturer" "Texas Instruments" (at 320.04 103.505 0)
      (effects (font (size 1.27 1.27) (thickness 0.15)) (justify left bottom) hide)
    )
    (property "Author" "Antmicro" (at 347.98 109.855 0)
      (effects (font (size 1.27 1.27) (thickness 0.15)) (justify left bottom) hide)
    )
    (property "License" "Apache-2.0" (at 347.98 112.395 0)
      (effects (font (size 1.27 1.27) (thickness 0.15)) (justify left bottom) hide)
    )
    (pin "1")
    (pin "10")
    (pin "11")
    (pin "12")
    (pin "13")
    (pin "14")
    (pin "15")
    (pin "16")
    (pin "2")
    (pin "3")
    (pin "4")
    (pin "5")
    (pin "6")
    (pin "7")
    (pin "8")
    (pin "9")
    (instances
      (project "kria-k26-devboard"
        (path ""
          (reference "U43") (unit 1)
        )
      )
    )
  )

  (symbol (lib_id "kria-k26-devboard:TP_0.75mm_SMD") (at 22.86 99.695 90) (unit 1)
    (in_bom yes) (on_board yes) (dnp no) (fields_autoplaced)
    (property "Reference" "TP27" (at 25.4 96.5199 90)
      (effects (font (size 1.27 1.27)) (justify right))
    )
    (property "Value" "TP_0.75mm_SMD" (at 25.4 99.695 0)
      (effects (font (size 1.27 1.27) (thickness 0.15)) (justify left bottom) hide)
    )
    (property "Footprint" "kria-k26-devboard-footprints:TP_SMD_0.75mm" (at 17.78 94.615 0)
      (effects (font (size 1.27 1.27) (thickness 0.15)) (justify left bottom) hide)
    )
    (property "Datasheet" "" (at 15.24 94.615 0)
      (effects (font (size 1.27 1.27) (thickness 0.15)) (justify left bottom) hide)
    )
    (property "MPN" "" (at 22.86 99.695 0)
      (effects (font (size 1.27 1.27) (thickness 0.15)) (justify left bottom) hide)
    )
    (property "Manufacturer" "" (at 22.86 99.695 0)
      (effects (font (size 1.27 1.27) (thickness 0.15)) (justify left bottom) hide)
    )
    (property "Author" "Antmicro" (at 38.1 84.455 0)
      (effects (font (size 1.27 1.27) (thickness 0.15)) (justify left bottom) hide)
    )
    (property "License" "Apache-2.0" (at 40.64 84.455 0)
      (effects (font (size 1.27 1.27) (thickness 0.15)) (justify left bottom) hide)
    )
    (pin "1")
    (instances
      (project "kria-k26-devboard"
        (path ""
          (reference "TP27") (unit 1)
        )
      )
    )
  )

  (symbol (lib_id "kria-k26-devboard:TP_0.75mm_SMD") (at 22.86 121.92 90) (unit 1)
    (in_bom yes) (on_board yes) (dnp no) (fields_autoplaced)
    (property "Reference" "TP24" (at 24.765 118.7449 90)
      (effects (font (size 1.27 1.27)) (justify right))
    )
    (property "Value" "TP_0.75mm_SMD" (at 25.4 121.92 0)
      (effects (font (size 1.27 1.27) (thickness 0.15)) (justify left bottom) hide)
    )
    (property "Footprint" "kria-k26-devboard-footprints:TP_SMD_0.75mm" (at 17.78 116.84 0)
      (effects (font (size 1.27 1.27) (thickness 0.15)) (justify left bottom) hide)
    )
    (property "Datasheet" "" (at 15.24 116.84 0)
      (effects (font (size 1.27 1.27) (thickness 0.15)) (justify left bottom) hide)
    )
    (property "MPN" "" (at 22.86 121.92 0)
      (effects (font (size 1.27 1.27) (thickness 0.15)) (justify left bottom) hide)
    )
    (property "Manufacturer" "" (at 22.86 121.92 0)
      (effects (font (size 1.27 1.27) (thickness 0.15)) (justify left bottom) hide)
    )
    (property "Author" "Antmicro" (at 38.1 106.68 0)
      (effects (font (size 1.27 1.27) (thickness 0.15)) (justify left bottom) hide)
    )
    (property "License" "Apache-2.0" (at 40.64 106.68 0)
      (effects (font (size 1.27 1.27) (thickness 0.15)) (justify left bottom) hide)
    )
    (pin "1")
    (instances
      (project "kria-k26-devboard"
        (path ""
          (reference "TP24") (unit 1)
        )
      )
    )
  )

  (symbol (lib_id "kria-k26-devboard:TP_0.75mm_SMD") (at 51.308 151.13 90) (unit 1)
    (in_bom yes) (on_board yes) (dnp no) (fields_autoplaced)
    (property "Reference" "TP28" (at 53.848 147.9549 90)
      (effects (font (size 1.27 1.27)) (justify right))
    )
    (property "Value" "TP_0.75mm_SMD" (at 53.848 151.13 0)
      (effects (font (size 1.27 1.27) (thickness 0.15)) (justify left bottom) hide)
    )
    (property "Footprint" "kria-k26-devboard-footprints:TP_SMD_0.75mm" (at 46.228 146.05 0)
      (effects (font (size 1.27 1.27) (thickness 0.15)) (justify left bottom) hide)
    )
    (property "Datasheet" "" (at 43.688 146.05 0)
      (effects (font (size 1.27 1.27) (thickness 0.15)) (justify left bottom) hide)
    )
    (property "MPN" "" (at 51.308 151.13 0)
      (effects (font (size 1.27 1.27) (thickness 0.15)) (justify left bottom) hide)
    )
    (property "Manufacturer" "" (at 51.308 151.13 0)
      (effects (font (size 1.27 1.27) (thickness 0.15)) (justify left bottom) hide)
    )
    (property "Author" "Antmicro" (at 66.548 135.89 0)
      (effects (font (size 1.27 1.27) (thickness 0.15)) (justify left bottom) hide)
    )
    (property "License" "Apache-2.0" (at 69.088 135.89 0)
      (effects (font (size 1.27 1.27) (thickness 0.15)) (justify left bottom) hide)
    )
    (pin "1")
    (instances
      (project "kria-k26-devboard"
        (path ""
          (reference "TP28") (unit 1)
        )
      )
    )
  )

  (symbol (lib_id "kria-k26-devboard:TP_0.75mm_SMD") (at 51.308 175.26 90) (unit 1)
    (in_bom yes) (on_board yes) (dnp no) (fields_autoplaced)
    (property "Reference" "TP25" (at 53.848 172.0849 90)
      (effects (font (size 1.27 1.27)) (justify right))
    )
    (property "Value" "TP_0.75mm_SMD" (at 53.848 175.26 0)
      (effects (font (size 1.27 1.27) (thickness 0.15)) (justify left bottom) hide)
    )
    (property "Footprint" "kria-k26-devboard-footprints:TP_SMD_0.75mm" (at 46.228 170.18 0)
      (effects (font (size 1.27 1.27) (thickness 0.15)) (justify left bottom) hide)
    )
    (property "Datasheet" "" (at 43.688 170.18 0)
      (effects (font (size 1.27 1.27) (thickness 0.15)) (justify left bottom) hide)
    )
    (property "MPN" "" (at 51.308 175.26 0)
      (effects (font (size 1.27 1.27) (thickness 0.15)) (justify left bottom) hide)
    )
    (property "Manufacturer" "" (at 51.308 175.26 0)
      (effects (font (size 1.27 1.27) (thickness 0.15)) (justify left bottom) hide)
    )
    (property "Author" "Antmicro" (at 66.548 160.02 0)
      (effects (font (size 1.27 1.27) (thickness 0.15)) (justify left bottom) hide)
    )
    (property "License" "Apache-2.0" (at 69.088 160.02 0)
      (effects (font (size 1.27 1.27) (thickness 0.15)) (justify left bottom) hide)
    )
    (pin "1")
    (instances
      (project "kria-k26-devboard"
        (path ""
          (reference "TP25") (unit 1)
        )
      )
    )
  )

  (symbol (lib_id "kria-k26-devboard:TP_0.75mm_SMD") (at 51.308 200.66 90) (unit 1)
    (in_bom yes) (on_board yes) (dnp no) (fields_autoplaced)
    (property "Reference" "TP26" (at 53.848 197.4849 90)
      (effects (font (size 1.27 1.27)) (justify right))
    )
    (property "Value" "TP_0.75mm_SMD" (at 53.848 200.66 0)
      (effects (font (size 1.27 1.27) (thickness 0.15)) (justify left bottom) hide)
    )
    (property "Footprint" "kria-k26-devboard-footprints:TP_SMD_0.75mm" (at 46.228 195.58 0)
      (effects (font (size 1.27 1.27) (thickness 0.15)) (justify left bottom) hide)
    )
    (property "Datasheet" "" (at 43.688 195.58 0)
      (effects (font (size 1.27 1.27) (thickness 0.15)) (justify left bottom) hide)
    )
    (property "MPN" "" (at 51.308 200.66 0)
      (effects (font (size 1.27 1.27) (thickness 0.15)) (justify left bottom) hide)
    )
    (property "Manufacturer" "" (at 51.308 200.66 0)
      (effects (font (size 1.27 1.27) (thickness 0.15)) (justify left bottom) hide)
    )
    (property "Author" "Antmicro" (at 66.548 185.42 0)
      (effects (font (size 1.27 1.27) (thickness 0.15)) (justify left bottom) hide)
    )
    (property "License" "Apache-2.0" (at 69.088 185.42 0)
      (effects (font (size 1.27 1.27) (thickness 0.15)) (justify left bottom) hide)
    )
    (pin "1")
    (instances
      (project "kria-k26-devboard"
        (path ""
          (reference "TP26") (unit 1)
        )
      )
    )
  )

  (symbol (lib_id "kria-k26-devboard:TP_0.75mm_SMD") (at 321.31 219.71 90) (unit 1)
    (in_bom yes) (on_board yes) (dnp no) (fields_autoplaced)
    (property "Reference" "TP33" (at 323.215 216.5349 90)
      (effects (font (size 1.27 1.27)) (justify right))
    )
    (property "Value" "TP_0.75mm_SMD" (at 323.85 219.71 0)
      (effects (font (size 1.27 1.27) (thickness 0.15)) (justify left bottom) hide)
    )
    (property "Footprint" "kria-k26-devboard-footprints:TP_SMD_0.75mm" (at 316.23 214.63 0)
      (effects (font (size 1.27 1.27) (thickness 0.15)) (justify left bottom) hide)
    )
    (property "Datasheet" "" (at 313.69 214.63 0)
      (effects (font (size 1.27 1.27) (thickness 0.15)) (justify left bottom) hide)
    )
    (property "MPN" "" (at 321.31 219.71 0)
      (effects (font (size 1.27 1.27) (thickness 0.15)) (justify left bottom) hide)
    )
    (property "Manufacturer" "" (at 321.31 219.71 0)
      (effects (font (size 1.27 1.27) (thickness 0.15)) (justify left bottom) hide)
    )
    (property "Author" "Antmicro" (at 336.55 204.47 0)
      (effects (font (size 1.27 1.27) (thickness 0.15)) (justify left bottom) hide)
    )
    (property "License" "Apache-2.0" (at 339.09 204.47 0)
      (effects (font (size 1.27 1.27) (thickness 0.15)) (justify left bottom) hide)
    )
    (pin "1")
    (instances
      (project "kria-k26-devboard"
        (path ""
          (reference "TP33") (unit 1)
        )
      )
    )
  )

  (symbol (lib_id "kria-k26-devboard:1N4148WS") (at 37.465 222.377 0) (unit 1)
    (in_bom yes) (on_board yes) (dnp no)
    (property "Reference" "D6" (at 38.1 221.234 0)
      (effects (font (size 1.524 1.524)))
    )
    (property "Value" "1N4148WS" (at 48.26 221.234 0)
      (effects (font (size 1.27 1.27) (thickness 0.15)))
    )
    (property "Footprint" "kria-k26-devboard-footprints:D_SOD-323F" (at 42.545 217.297 0)
      (effects (font (size 1.27 1.27) (thickness 0.15)) (justify left bottom) hide)
    )
    (property "Datasheet" "https://www.onsemi.com/pub/Collateral/1N914BWS-D.pdf" (at 42.545 214.757 0)
      (effects (font (size 1.27 1.27) (thickness 0.15)) (justify left bottom) hide)
    )
    (property "MPN" "1N4148WS" (at 42.545 209.677 0)
      (effects (font (size 1.27 1.27) (thickness 0.15)) (justify left bottom) hide)
    )
    (property "Manufacturer" "ON Semiconductor" (at 42.545 194.437 0)
      (effects (font (size 1.27 1.27) (thickness 0.15)) (justify left bottom) hide)
    )
    (property "Author" "Antmicro" (at 59.055 242.697 0)
      (effects (font (size 1.27 1.27) (thickness 0.15)) (justify left bottom) hide)
    )
    (property "License" "Apache-2.0" (at 59.055 245.237 0)
      (effects (font (size 1.27 1.27) (thickness 0.15)) (justify left bottom) hide)
    )
    (pin "A")
    (pin "K")
    (instances
      (project "kria-k26-devboard"
        (path ""
          (reference "D6") (unit 1)
        )
      )
    )
  )

  (symbol (lib_id "kria-k26-devboard:1N4148WS") (at 37.465 230.759 0) (unit 1)
    (in_bom yes) (on_board yes) (dnp no)
    (property "Reference" "D7" (at 38.1 229.489 0)
      (effects (font (size 1.524 1.524)))
    )
    (property "Value" "1N4148WS" (at 48.26 229.489 0)
      (effects (font (size 1.27 1.27) (thickness 0.15)))
    )
    (property "Footprint" "kria-k26-devboard-footprints:D_SOD-323F" (at 42.545 225.679 0)
      (effects (font (size 1.27 1.27) (thickness 0.15)) (justify left bottom) hide)
    )
    (property "Datasheet" "https://www.onsemi.com/pub/Collateral/1N914BWS-D.pdf" (at 42.545 223.139 0)
      (effects (font (size 1.27 1.27) (thickness 0.15)) (justify left bottom) hide)
    )
    (property "MPN" "1N4148WS" (at 42.545 218.059 0)
      (effects (font (size 1.27 1.27) (thickness 0.15)) (justify left bottom) hide)
    )
    (property "Manufacturer" "ON Semiconductor" (at 42.545 202.819 0)
      (effects (font (size 1.27 1.27) (thickness 0.15)) (justify left bottom) hide)
    )
    (property "Author" "Antmicro" (at 59.055 251.079 0)
      (effects (font (size 1.27 1.27) (thickness 0.15)) (justify left bottom) hide)
    )
    (property "License" "Apache-2.0" (at 59.055 253.619 0)
      (effects (font (size 1.27 1.27) (thickness 0.15)) (justify left bottom) hide)
    )
    (pin "A")
    (pin "K")
    (instances
      (project "kria-k26-devboard"
        (path ""
          (reference "D7") (unit 1)
        )
      )
    )
  )

  (symbol (lib_id "kria-k26-devboard:DTC014T_SOT-416") (at 209.55 60.96 0) (unit 1)
    (in_bom yes) (on_board yes) (dnp no) (fields_autoplaced)
    (property "Reference" "Q10" (at 219.71 59.6899 0)
      (effects (font (size 1.27 1.27)) (justify left))
    )
    (property "Value" "DTC014T_SOT-416" (at 219.71 62.2299 0)
      (effects (font (size 1.27 1.27) (thickness 0.15)) (justify left) hide)
    )
    (property "Footprint" "kria-k26-devboard-footprints:SOT-416" (at 214.63 68.58 0)
      (effects (font (size 1.27 1.27) (thickness 0.15)) (justify left bottom) hide)
    )
    (property "Datasheet" "https://www.rohm.com/datasheet?p=DTC014TEB&dist=Mouser&media=referral&source=mouser.com&campaign=Mouser" (at 209.55 60.96 0)
      (effects (font (size 1.27 1.27) (thickness 0.15)) (justify left bottom) hide)
    )
    (property "Manufacturer" "ROHM Semiconductor" (at 224.79 63.5 0)
      (effects (font (size 1.27 1.27) (thickness 0.15)) (justify left bottom) hide)
    )
    (property "MPN" "DTC014TEBTL" (at 219.71 62.2299 0)
      (effects (font (size 1.27 1.27) (thickness 0.15)) (justify left))
    )
    (property "Author" "Antmicro" (at 234.95 81.28 0)
      (effects (font (size 1.27 1.27) (thickness 0.15)) (justify left bottom) hide)
    )
    (property "License" "Apache-2.0" (at 234.95 83.82 0)
      (effects (font (size 1.27 1.27) (thickness 0.15)) (justify left bottom) hide)
    )
    (pin "1")
    (pin "2")
    (pin "3")
    (instances
      (project "kria-k26-devboard"
        (path ""
          (reference "Q10") (unit 1)
        )
      )
    )
  )

  (symbol (lib_id "kria-k26-devboard:GND") (at 321.31 233.68 0) (unit 1)
    (in_bom yes) (on_board yes) (dnp no) (fields_autoplaced)
    (property "Reference" "#PWR0354" (at 321.31 240.03 0)
      (effects (font (size 1.27 1.27)) hide)
    )
    (property "Value" "GND" (at 321.31 238.76 0)
      (effects (font (size 1.27 1.27)))
    )
    (property "Footprint" "" (at 330.2 241.3 0)
      (effects (font (size 1.27 1.27) (thickness 0.15)) (justify left bottom) hide)
    )
    (property "Datasheet" "" (at 330.2 246.38 0)
      (effects (font (size 1.27 1.27) (thickness 0.15)) (justify left bottom) hide)
    )
    (property "Author" "Antmicro" (at 330.2 241.3 0)
      (effects (font (size 1.27 1.27) (thickness 0.15)) (justify left bottom) hide)
    )
    (property "License" "Apache-2.0" (at 330.2 243.84 0)
      (effects (font (size 1.27 1.27) (thickness 0.15)) (justify left bottom) hide)
    )
    (pin "1")
    (instances
      (project "kria-k26-devboard"
        (path ""
          (reference "#PWR0354") (unit 1)
        )
      )
    )
  )

  (symbol (lib_id "kria-k26-devboard:GND") (at 54.61 41.91 0) (unit 1)
    (in_bom yes) (on_board yes) (dnp no)
    (property "Reference" "#PWR0326" (at 54.61 48.26 0)
      (effects (font (size 1.27 1.27)) hide)
    )
    (property "Value" "GND" (at 54.61 45.72 0)
      (effects (font (size 1.27 1.27)))
    )
    (property "Footprint" "" (at 63.5 49.53 0)
      (effects (font (size 1.27 1.27) (thickness 0.15)) (justify left bottom) hide)
    )
    (property "Datasheet" "" (at 63.5 54.61 0)
      (effects (font (size 1.27 1.27) (thickness 0.15)) (justify left bottom) hide)
    )
    (property "Author" "Antmicro" (at 63.5 49.53 0)
      (effects (font (size 1.27 1.27) (thickness 0.15)) (justify left bottom) hide)
    )
    (property "License" "Apache-2.0" (at 63.5 52.07 0)
      (effects (font (size 1.27 1.27) (thickness 0.15)) (justify left bottom) hide)
    )
    (pin "1")
    (instances
      (project "kria-k26-devboard"
        (path ""
          (reference "#PWR0326") (unit 1)
        )
      )
    )
  )

  (symbol (lib_id "kria-k26-devboard:C_100n_50V_0402") (at 54.61 34.29 270) (unit 1)
    (in_bom yes) (on_board yes) (dnp no)
    (property "Reference" "C153" (at 55.245 34.925 90)
      (effects (font (size 1.27 1.27)) (justify left))
    )
    (property "Value" "C_100n_50V_0402" (at 54.61 34.29 0)
      (effects (font (size 1.27 1.27) (thickness 0.15)) (justify left bottom) hide)
    )
    (property "Footprint" "kria-k26-devboard-footprints:C_0402_1005Metric" (at 54.61 34.29 0)
      (effects (font (size 1.27 1.27) (thickness 0.15)) (justify left bottom) hide)
    )
    (property "Datasheet" " " (at 54.61 34.29 0)
      (effects (font (size 1.27 1.27) (thickness 0.15)) (justify left bottom) hide)
    )
    (property "MPN" "GRM155R71H104KE14D" (at 54.61 34.29 0)
      (effects (font (size 1.27 1.27) (thickness 0.15)) (justify left bottom) hide)
    )
    (property "Manufacturer" "Murata" (at 54.61 34.29 0)
      (effects (font (size 1.27 1.27) (thickness 0.15)) (justify left bottom) hide)
    )
    (property "Val" "100n/50V" (at 55.245 38.735 90)
      (effects (font (size 1.27 1.27) (thickness 0.15)) (justify left))
    )
    (property "License" "Apache-2.0" (at 31.75 54.61 0)
      (effects (font (size 1.27 1.27) (thickness 0.15)) (justify left bottom) hide)
    )
    (property "Author" "Antmicro" (at 29.21 54.61 0)
      (effects (font (size 1.27 1.27) (thickness 0.15)) (justify left bottom) hide)
    )
    (property "Voltage" "" (at 26.67 54.61 0)
      (effects (font (size 1.27 1.27)) (justify left bottom) hide)
    )
    (property "Dielectric" "" (at 24.13 54.61 0)
      (effects (font (size 1.27 1.27)) (justify left bottom) hide)
    )
    (pin "1")
    (pin "2")
    (instances
      (project "kria-k26-devboard"
        (path ""
          (reference "C153") (unit 1)
        )
      )
    )
  )

  (symbol (lib_id "kria-k26-devboard:USB-C_GCT_USB4105-GF-A") (at 36.195 35.56 0) (unit 1)
    (in_bom yes) (on_board yes) (dnp yes) (fields_autoplaced)
    (property "Reference" "J8" (at 22.86 25.4 0)
      (effects (font (size 1.27 1.27)))
    )
    (property "Value" "USB-C_GCT_USB4105-GF-A" (at 46.6725 27.305 0)
      (effects (font (size 1.27 1.27) (thickness 0.15)) hide)
    )
    (property "Footprint" "kria-k26-devboard-footprints:USB-C_Receptacle_GCT_USB4105-GF-A" (at 19.685 29.21 0)
      (effects (font (size 1.27 1.27) (thickness 0.15)) (justify left bottom) hide)
    )
    (property "Datasheet" "https://gct.co/files/drawings/usb4105.pdf" (at 36.195 35.56 0)
      (effects (font (size 1.27 1.27) (thickness 0.15)) (justify left bottom) hide)
    )
    (property "Manufacturer" "GCT" (at 19.685 26.67 0)
      (effects (font (size 1.27 1.27) (thickness 0.15)) (justify left bottom) hide)
    )
    (property "MPN" "USB4105-GF-A" (at 22.86 27.94 0)
      (effects (font (size 1.27 1.27) (thickness 0.15)))
    )
    (property "DNP" "DNP" (at 22.86 30.48 0)
      (effects (font (size 1.27 1.27)))
    )
    (property "Author" "Antmicro" (at 74.295 53.34 0)
      (effects (font (size 1.27 1.27) (thickness 0.15)) (justify left bottom) hide)
    )
    (property "License" "Apache-2.0" (at 74.295 55.88 0)
      (effects (font (size 1.27 1.27) (thickness 0.15)) (justify left bottom) hide)
    )
    (property "VSD_Class" "USB-C" (at 74.295 58.42 0)
      (effects (font (size 1.27 1.27)) (justify left bottom) hide)
    )
    (pin "A1")
    (pin "A12")
    (pin "A4")
    (pin "A5")
    (pin "A6")
    (pin "A7")
    (pin "A8")
    (pin "A9")
    (pin "B1")
    (pin "B12")
    (pin "B4")
    (pin "B5")
    (pin "B6")
    (pin "B7")
    (pin "B8")
    (pin "B9")
    (pin "SH")
    (instances
      (project "kria-k26-devboard"
        (path ""
          (reference "J8") (unit 1)
        )
      )
    )
  )

  (symbol (lib_id "kria-k26-devboard:PinHeader_2x7_P2mm_Drill1mm_Shrouded") (at 219.71 256.54 0) (unit 1)
    (in_bom yes) (on_board yes) (dnp no)
    (property "Reference" "J9" (at 224.79 250.825 0)
      (effects (font (size 1.27 1.27)))
    )
    (property "Value" "PinHeader_2x7_P2mm_Drill1mm_Shrouded" (at 245.11 261.62 0)
      (effects (font (size 1.27 1.27) (thickness 0.15)) (justify left bottom) hide)
    )
    (property "Footprint" "kria-k26-devboard-footprints:PinHeader_2x7_P2mm_Drill1mm_Shrouded" (at 245.11 264.16 0)
      (effects (font (size 1.27 1.27) (thickness 0.15)) (justify left bottom) hide)
    )
    (property "Datasheet" "https://www.molex.com/pdm_docs/sd/878322620_sd.pdf" (at 245.11 266.7 0)
      (effects (font (size 1.27 1.27) (thickness 0.15)) (justify left bottom) hide)
    )
    (property "MPN" "0878311420" (at 224.79 253.365 0)
      (effects (font (size 1.27 1.27) (thickness 0.15)))
    )
    (property "Manufacturer" "Molex" (at 245.11 271.78 0)
      (effects (font (size 1.27 1.27) (thickness 0.15)) (justify left bottom) hide)
    )
    (property "Author" "Antmicro" (at 245.11 274.32 0)
      (effects (font (size 1.27 1.27) (thickness 0.15)) (justify left bottom) hide)
    )
    (property "License" "Apache-2.0" (at 245.11 276.86 0)
      (effects (font (size 1.27 1.27) (thickness 0.15)) (justify left bottom) hide)
    )
    (pin "1")
    (pin "10")
    (pin "11")
    (pin "12")
    (pin "13")
    (pin "14")
    (pin "2")
    (pin "3")
    (pin "4")
    (pin "5")
    (pin "6")
    (pin "7")
    (pin "8")
    (pin "9")
    (instances
      (project "kria-k26-devboard"
        (path ""
          (reference "J9") (unit 1)
        )
      )
    )
  )

  (symbol (lib_id "kria-k26-devboard:C_100n_0402") (at 238.76 245.11 270) (unit 1)
    (in_bom yes) (on_board yes) (dnp no) (fields_autoplaced)
    (property "Reference" "C161" (at 241.3 246.3863 90)
      (effects (font (size 1.524 1.524)) (justify left))
    )
    (property "Value" "C_100n_0402" (at 234.95 245.11 0)
      (effects (font (size 1.27 1.27) (thickness 0.15)) (justify left bottom) hide)
    )
    (property "Footprint" "kria-k26-devboard-footprints:C_0402_1005Metric" (at 243.84 250.19 0)
      (effects (font (size 1.27 1.27) (thickness 0.15)) (justify left bottom) hide)
    )
    (property "Datasheet" "https://search.murata.co.jp/Ceramy/image/img/A01X/G101/ENG/GRM155R61H104KE14-01.pdf" (at 238.76 245.11 0)
      (effects (font (size 1.27 1.27) (thickness 0.15)) (justify left bottom) hide)
    )
    (property "Manufacturer" "Murata" (at 248.92 250.19 0)
      (effects (font (size 1.27 1.27) (thickness 0.15)) (justify left bottom) hide)
    )
    (property "MPN" "GRM155R61H104KE14D" (at 246.38 250.19 0)
      (effects (font (size 1.27 1.27) (thickness 0.15)) (justify left bottom) hide)
    )
    (property "Val" "100n" (at 241.3 249.5612 90)
      (effects (font (size 1.27 1.27) (thickness 0.15)) (justify left))
    )
    (property "License" "Apache-2.0" (at 215.9 265.43 0)
      (effects (font (size 1.27 1.27) (thickness 0.15)) (justify left bottom) hide)
    )
    (property "Author" "Antmicro" (at 213.36 265.43 0)
      (effects (font (size 1.27 1.27) (thickness 0.15)) (justify left bottom) hide)
    )
    (property "Voltage" "50V" (at 210.82 265.43 0)
      (effects (font (size 1.27 1.27)) (justify left bottom) hide)
    )
    (property "Dielectric" "X5R" (at 208.28 265.43 0)
      (effects (font (size 1.27 1.27)) (justify left bottom) hide)
    )
    (pin "1")
    (pin "2")
    (instances
      (project "kria-k26-devboard"
        (path ""
          (reference "C161") (unit 1)
        )
      )
    )
  )

  (symbol (lib_id "kria-k26-devboard:GND") (at 238.76 250.19 0) (unit 1)
    (in_bom yes) (on_board yes) (dnp no) (fields_autoplaced)
    (property "Reference" "#PWR0342" (at 238.76 256.54 0)
      (effects (font (size 1.27 1.27)) hide)
    )
    (property "Value" "GND" (at 238.76 255.27 0)
      (effects (font (size 1.27 1.27)))
    )
    (property "Footprint" "" (at 247.65 257.81 0)
      (effects (font (size 1.27 1.27) (thickness 0.15)) (justify left bottom) hide)
    )
    (property "Datasheet" "" (at 247.65 262.89 0)
      (effects (font (size 1.27 1.27) (thickness 0.15)) (justify left bottom) hide)
    )
    (property "Author" "Antmicro" (at 247.65 257.81 0)
      (effects (font (size 1.27 1.27) (thickness 0.15)) (justify left bottom) hide)
    )
    (property "License" "Apache-2.0" (at 247.65 260.35 0)
      (effects (font (size 1.27 1.27) (thickness 0.15)) (justify left bottom) hide)
    )
    (pin "1")
    (instances
      (project "kria-k26-devboard"
        (path ""
          (reference "#PWR0342") (unit 1)
        )
      )
    )
  )

  (symbol (lib_id "kria-k26-devboard:GND") (at 218.44 274.32 0) (unit 1)
    (in_bom yes) (on_board yes) (dnp no) (fields_autoplaced)
    (property "Reference" "#PWR0340" (at 218.44 280.67 0)
      (effects (font (size 1.27 1.27)) hide)
    )
    (property "Value" "GND" (at 218.44 279.4 0)
      (effects (font (size 1.27 1.27)))
    )
    (property "Footprint" "" (at 227.33 281.94 0)
      (effects (font (size 1.27 1.27) (thickness 0.15)) (justify left bottom) hide)
    )
    (property "Datasheet" "" (at 227.33 287.02 0)
      (effects (font (size 1.27 1.27) (thickness 0.15)) (justify left bottom) hide)
    )
    (property "Author" "Antmicro" (at 227.33 281.94 0)
      (effects (font (size 1.27 1.27) (thickness 0.15)) (justify left bottom) hide)
    )
    (property "License" "Apache-2.0" (at 227.33 284.48 0)
      (effects (font (size 1.27 1.27) (thickness 0.15)) (justify left bottom) hide)
    )
    (pin "1")
    (instances
      (project "kria-k26-devboard"
        (path ""
          (reference "#PWR0340") (unit 1)
        )
      )
    )
  )

  (symbol (lib_id "kria-k26-devboard:NC7WZ07_SC") (at 363.22 148.59 0) (unit 1)
    (in_bom yes) (on_board yes) (dnp no)
    (property "Reference" "U46" (at 370.84 141.605 0)
      (effects (font (size 1.524 1.524)))
    )
    (property "Value" "NC7WZ07_SC" (at 372.8594 139.7 0)
      (effects (font (size 1.27 1.27) (thickness 0.15)) (justify left bottom) hide)
    )
    (property "Footprint" "kria-k26-devboard-footprints:SOT-363" (at 368.3 143.51 0)
      (effects (font (size 1.27 1.27) (thickness 0.15)) (justify left bottom) hide)
    )
    (property "Datasheet" "https://www.onsemi.com/pub/Collateral/NC7WZ07-D.pdf" (at 368.3 140.97 0)
      (effects (font (size 1.27 1.27) (thickness 0.15)) (justify left bottom) hide)
    )
    (property "MPN" "NC7WZ07P6X" (at 370.84 144.145 0)
      (effects (font (size 1.27 1.27) (thickness 0.15)))
    )
    (property "Manufacturer" "ON Semiconductor" (at 368.3 120.65 0)
      (effects (font (size 1.27 1.27) (thickness 0.15)) (justify left bottom) hide)
    )
    (property "Author" "Antmicro" (at 393.7 170.18 0)
      (effects (font (size 1.27 1.27) (thickness 0.15)) (justify left bottom) hide)
    )
    (property "License" "Apache-2.0" (at 393.7 172.72 0)
      (effects (font (size 1.27 1.27) (thickness 0.15)) (justify left bottom) hide)
    )
    (pin "1")
    (pin "2")
    (pin "3")
    (pin "4")
    (pin "5")
    (pin "6")
    (instances
      (project "kria-k26-devboard"
        (path ""
          (reference "U46") (unit 1)
        )
      )
    )
  )

  (symbol (lib_id "kria-k26-devboard:R_10k_0402") (at 166.878 253.365 270) (unit 1)
    (in_bom yes) (on_board yes) (dnp no)
    (property "Reference" "R106" (at 168.148 255.27 90)
      (effects (font (size 1.524 1.524)) (justify left))
    )
    (property "Value" "R_10k_0402" (at 163.068 253.365 0)
      (effects (font (size 1.27 1.27) (thickness 0.15)) (justify left bottom) hide)
    )
    (property "Footprint" "kria-k26-devboard-footprints:R_0402_1005Metric" (at 171.958 258.445 0)
      (effects (font (size 1.27 1.27) (thickness 0.15)) (justify left bottom) hide)
    )
    (property "Datasheet" "https://www.bourns.com/docs/product-datasheets/cr.pdf" (at 166.878 253.365 0)
      (effects (font (size 1.27 1.27) (thickness 0.15)) (justify left bottom) hide)
    )
    (property "Manufacturer" "Bourns" (at 177.038 258.445 0)
      (effects (font (size 1.27 1.27) (thickness 0.15)) (justify left bottom) hide)
    )
    (property "MPN" "CR0402-FX-1002GLF" (at 174.498 258.445 0)
      (effects (font (size 1.27 1.27) (thickness 0.15)) (justify left bottom) hide)
    )
    (property "Val" "10k" (at 168.148 257.1749 90)
      (effects (font (size 1.27 1.27) (thickness 0.15)) (justify left))
    )
    (property "License" "Apache-2.0" (at 141.478 273.685 0)
      (effects (font (size 1.27 1.27) (thickness 0.15)) (justify left bottom) hide)
    )
    (property "Author" "Antmicro" (at 138.938 273.685 0)
      (effects (font (size 1.27 1.27) (thickness 0.15)) (justify left bottom) hide)
    )
    (property "Tolerance" "1%" (at 156.718 273.685 0)
      (effects (font (size 1.27 1.27)) (justify left bottom) hide)
    )
    (pin "1")
    (pin "2")
    (instances
      (project "kria-k26-devboard"
        (path ""
          (reference "R106") (unit 1)
        )
      )
    )
  )

  (symbol (lib_id "kria-k26-devboard:C_100n_0402") (at 319.405 140.335 270) (unit 1)
    (in_bom yes) (on_board yes) (dnp no) (fields_autoplaced)
    (property "Reference" "C167" (at 322.58 141.6113 90)
      (effects (font (size 1.524 1.524)) (justify left))
    )
    (property "Value" "C_100n_0402" (at 315.595 140.335 0)
      (effects (font (size 1.27 1.27) (thickness 0.15)) (justify left bottom) hide)
    )
    (property "Footprint" "kria-k26-devboard-footprints:C_0402_1005Metric" (at 324.485 145.415 0)
      (effects (font (size 1.27 1.27) (thickness 0.15)) (justify left bottom) hide)
    )
    (property "Datasheet" "https://search.murata.co.jp/Ceramy/image/img/A01X/G101/ENG/GRM155R61H104KE14-01.pdf" (at 319.405 140.335 0)
      (effects (font (size 1.27 1.27) (thickness 0.15)) (justify left bottom) hide)
    )
    (property "Manufacturer" "Murata" (at 329.565 145.415 0)
      (effects (font (size 1.27 1.27) (thickness 0.15)) (justify left bottom) hide)
    )
    (property "MPN" "GRM155R61H104KE14D" (at 327.025 145.415 0)
      (effects (font (size 1.27 1.27) (thickness 0.15)) (justify left bottom) hide)
    )
    (property "Val" "100n" (at 322.58 144.7862 90)
      (effects (font (size 1.27 1.27) (thickness 0.15)) (justify left))
    )
    (property "License" "Apache-2.0" (at 296.545 160.655 0)
      (effects (font (size 1.27 1.27) (thickness 0.15)) (justify left bottom) hide)
    )
    (property "Author" "Antmicro" (at 294.005 160.655 0)
      (effects (font (size 1.27 1.27) (thickness 0.15)) (justify left bottom) hide)
    )
    (property "Voltage" "50V" (at 291.465 160.655 0)
      (effects (font (size 1.27 1.27)) (justify left bottom) hide)
    )
    (property "Dielectric" "X5R" (at 288.925 160.655 0)
      (effects (font (size 1.27 1.27)) (justify left bottom) hide)
    )
    (pin "1")
    (pin "2")
    (instances
      (project "kria-k26-devboard"
        (path ""
          (reference "C167") (unit 1)
        )
      )
    )
  )

  (symbol (lib_id "kria-k26-devboard:GND") (at 319.405 145.415 0) (unit 1)
    (in_bom yes) (on_board yes) (dnp no) (fields_autoplaced)
    (property "Reference" "#PWR0358" (at 319.405 151.765 0)
      (effects (font (size 1.27 1.27)) hide)
    )
    (property "Value" "GND" (at 319.405 149.987 0)
      (effects (font (size 1.27 1.27)))
    )
    (property "Footprint" "" (at 328.295 153.035 0)
      (effects (font (size 1.27 1.27) (thickness 0.15)) (justify left bottom) hide)
    )
    (property "Datasheet" "" (at 328.295 158.115 0)
      (effects (font (size 1.27 1.27) (thickness 0.15)) (justify left bottom) hide)
    )
    (property "Author" "Antmicro" (at 328.295 153.035 0)
      (effects (font (size 1.27 1.27) (thickness 0.15)) (justify left bottom) hide)
    )
    (property "License" "Apache-2.0" (at 328.295 155.575 0)
      (effects (font (size 1.27 1.27) (thickness 0.15)) (justify left bottom) hide)
    )
    (pin "1")
    (instances
      (project "kria-k26-devboard"
        (path ""
          (reference "#PWR0358") (unit 1)
        )
      )
    )
  )

  (symbol (lib_id "kria-k26-devboard:C_100n_0402") (at 352.425 139.7 90) (mirror x) (unit 1)
    (in_bom yes) (on_board yes) (dnp no) (fields_autoplaced)
    (property "Reference" "C170" (at 355.6 140.9763 90)
      (effects (font (size 1.524 1.524)) (justify right))
    )
    (property "Value" "C_100n_0402" (at 356.235 139.7 0)
      (effects (font (size 1.27 1.27) (thickness 0.15)) (justify left bottom) hide)
    )
    (property "Footprint" "kria-k26-devboard-footprints:C_0402_1005Metric" (at 347.345 144.78 0)
      (effects (font (size 1.27 1.27) (thickness 0.15)) (justify left bottom) hide)
    )
    (property "Datasheet" "https://search.murata.co.jp/Ceramy/image/img/A01X/G101/ENG/GRM155R61H104KE14-01.pdf" (at 352.425 139.7 0)
      (effects (font (size 1.27 1.27) (thickness 0.15)) (justify left bottom) hide)
    )
    (property "Manufacturer" "Murata" (at 342.265 144.78 0)
      (effects (font (size 1.27 1.27) (thickness 0.15)) (justify left bottom) hide)
    )
    (property "MPN" "GRM155R61H104KE14D" (at 344.805 144.78 0)
      (effects (font (size 1.27 1.27) (thickness 0.15)) (justify left bottom) hide)
    )
    (property "Val" "100n" (at 355.6 144.1512 90)
      (effects (font (size 1.27 1.27) (thickness 0.15)) (justify right))
    )
    (property "License" "Apache-2.0" (at 375.285 160.02 0)
      (effects (font (size 1.27 1.27) (thickness 0.15)) (justify left bottom) hide)
    )
    (property "Author" "Antmicro" (at 377.825 160.02 0)
      (effects (font (size 1.27 1.27) (thickness 0.15)) (justify left bottom) hide)
    )
    (property "Voltage" "50V" (at 380.365 160.02 0)
      (effects (font (size 1.27 1.27)) (justify left bottom) hide)
    )
    (property "Dielectric" "X5R" (at 382.905 160.02 0)
      (effects (font (size 1.27 1.27)) (justify left bottom) hide)
    )
    (pin "1")
    (pin "2")
    (instances
      (project "kria-k26-devboard"
        (path ""
          (reference "C170") (unit 1)
        )
      )
    )
  )

  (symbol (lib_id "kria-k26-devboard:GND") (at 352.425 144.78 0) (mirror y) (unit 1)
    (in_bom yes) (on_board yes) (dnp no) (fields_autoplaced)
    (property "Reference" "#PWR0361" (at 352.425 151.13 0)
      (effects (font (size 1.27 1.27)) hide)
    )
    (property "Value" "GND" (at 352.425 149.352 0)
      (effects (font (size 1.27 1.27)))
    )
    (property "Footprint" "" (at 343.535 152.4 0)
      (effects (font (size 1.27 1.27) (thickness 0.15)) (justify left bottom) hide)
    )
    (property "Datasheet" "" (at 343.535 157.48 0)
      (effects (font (size 1.27 1.27) (thickness 0.15)) (justify left bottom) hide)
    )
    (property "Author" "Antmicro" (at 343.535 152.4 0)
      (effects (font (size 1.27 1.27) (thickness 0.15)) (justify left bottom) hide)
    )
    (property "License" "Apache-2.0" (at 343.535 154.94 0)
      (effects (font (size 1.27 1.27) (thickness 0.15)) (justify left bottom) hide)
    )
    (pin "1")
    (instances
      (project "kria-k26-devboard"
        (path ""
          (reference "#PWR0361") (unit 1)
        )
      )
    )
  )

  (symbol (lib_id "kria-k26-devboard:GND") (at 278.13 156.21 0) (mirror y) (unit 1)
    (in_bom yes) (on_board yes) (dnp no) (fields_autoplaced)
    (property "Reference" "#PWR0347" (at 278.13 162.56 0)
      (effects (font (size 1.27 1.27)) hide)
    )
    (property "Value" "GND" (at 278.13 161.29 0)
      (effects (font (size 1.27 1.27)))
    )
    (property "Footprint" "" (at 269.24 163.83 0)
      (effects (font (size 1.27 1.27) (thickness 0.15)) (justify left bottom) hide)
    )
    (property "Datasheet" "" (at 269.24 168.91 0)
      (effects (font (size 1.27 1.27) (thickness 0.15)) (justify left bottom) hide)
    )
    (property "Author" "Antmicro" (at 269.24 163.83 0)
      (effects (font (size 1.27 1.27) (thickness 0.15)) (justify left bottom) hide)
    )
    (property "License" "Apache-2.0" (at 269.24 166.37 0)
      (effects (font (size 1.27 1.27) (thickness 0.15)) (justify left bottom) hide)
    )
    (pin "1")
    (instances
      (project "kria-k26-devboard"
        (path ""
          (reference "#PWR0347") (unit 1)
        )
      )
    )
  )

  (symbol (lib_id "kria-k26-devboard:C_100n_0402") (at 278.13 151.13 90) (mirror x) (unit 1)
    (in_bom yes) (on_board yes) (dnp no) (fields_autoplaced)
    (property "Reference" "C165" (at 274.955 152.4063 90)
      (effects (font (size 1.524 1.524)) (justify left))
    )
    (property "Value" "C_100n_0402" (at 281.94 151.13 0)
      (effects (font (size 1.27 1.27) (thickness 0.15)) (justify left bottom) hide)
    )
    (property "Footprint" "kria-k26-devboard-footprints:C_0402_1005Metric" (at 273.05 156.21 0)
      (effects (font (size 1.27 1.27) (thickness 0.15)) (justify left bottom) hide)
    )
    (property "Datasheet" "https://search.murata.co.jp/Ceramy/image/img/A01X/G101/ENG/GRM155R61H104KE14-01.pdf" (at 278.13 151.13 0)
      (effects (font (size 1.27 1.27) (thickness 0.15)) (justify left bottom) hide)
    )
    (property "Manufacturer" "Murata" (at 267.97 156.21 0)
      (effects (font (size 1.27 1.27) (thickness 0.15)) (justify left bottom) hide)
    )
    (property "MPN" "GRM155R61H104KE14D" (at 270.51 156.21 0)
      (effects (font (size 1.27 1.27) (thickness 0.15)) (justify left bottom) hide)
    )
    (property "Val" "100n" (at 274.955 155.5812 90)
      (effects (font (size 1.27 1.27) (thickness 0.15)) (justify left))
    )
    (property "License" "Apache-2.0" (at 300.99 171.45 0)
      (effects (font (size 1.27 1.27) (thickness 0.15)) (justify left bottom) hide)
    )
    (property "Author" "Antmicro" (at 303.53 171.45 0)
      (effects (font (size 1.27 1.27) (thickness 0.15)) (justify left bottom) hide)
    )
    (property "Voltage" "50V" (at 306.07 171.45 0)
      (effects (font (size 1.27 1.27)) (justify left bottom) hide)
    )
    (property "Dielectric" "X5R" (at 308.61 171.45 0)
      (effects (font (size 1.27 1.27)) (justify left bottom) hide)
    )
    (pin "1")
    (pin "2")
    (instances
      (project "kria-k26-devboard"
        (path ""
          (reference "C165") (unit 1)
        )
      )
    )
  )

  (symbol (lib_id "kria-k26-devboard:R_10k_0402") (at 339.725 140.335 270) (unit 1)
    (in_bom yes) (on_board yes) (dnp no) (fields_autoplaced)
    (property "Reference" "R113" (at 337.439 141.605 90)
      (effects (font (size 1.524 1.524)) (justify right))
    )
    (property "Value" "R_10k_0402" (at 335.915 140.335 0)
      (effects (font (size 1.27 1.27) (thickness 0.15)) (justify left bottom) hide)
    )
    (property "Footprint" "kria-k26-devboard-footprints:R_0402_1005Metric" (at 344.805 145.415 0)
      (effects (font (size 1.27 1.27) (thickness 0.15)) (justify left bottom) hide)
    )
    (property "Datasheet" "https://www.bourns.com/docs/product-datasheets/cr.pdf" (at 339.725 140.335 0)
      (effects (font (size 1.27 1.27) (thickness 0.15)) (justify left bottom) hide)
    )
    (property "Manufacturer" "Bourns" (at 349.885 145.415 0)
      (effects (font (size 1.27 1.27) (thickness 0.15)) (justify left bottom) hide)
    )
    (property "MPN" "CR0402-FX-1002GLF" (at 347.345 145.415 0)
      (effects (font (size 1.27 1.27) (thickness 0.15)) (justify left bottom) hide)
    )
    (property "Val" "10k" (at 337.439 144.7799 90)
      (effects (font (size 1.27 1.27) (thickness 0.15)) (justify right))
    )
    (property "License" "Apache-2.0" (at 314.325 160.655 0)
      (effects (font (size 1.27 1.27) (thickness 0.15)) (justify left bottom) hide)
    )
    (property "Author" "Antmicro" (at 311.785 160.655 0)
      (effects (font (size 1.27 1.27) (thickness 0.15)) (justify left bottom) hide)
    )
    (property "Tolerance" "1%" (at 329.565 160.655 0)
      (effects (font (size 1.27 1.27)) (justify left bottom) hide)
    )
    (pin "1")
    (pin "2")
    (instances
      (project "kria-k26-devboard"
        (path ""
          (reference "R113") (unit 1)
        )
      )
    )
  )

  (symbol (lib_id "kria-k26-devboard:R_10k_0402") (at 342.265 140.335 270) (unit 1)
    (in_bom yes) (on_board yes) (dnp no) (fields_autoplaced)
    (property "Reference" "R114" (at 344.043 141.605 90)
      (effects (font (size 1.524 1.524)) (justify left))
    )
    (property "Value" "R_10k_0402" (at 338.455 140.335 0)
      (effects (font (size 1.27 1.27) (thickness 0.15)) (justify left bottom) hide)
    )
    (property "Footprint" "kria-k26-devboard-footprints:R_0402_1005Metric" (at 347.345 145.415 0)
      (effects (font (size 1.27 1.27) (thickness 0.15)) (justify left bottom) hide)
    )
    (property "Datasheet" "https://www.bourns.com/docs/product-datasheets/cr.pdf" (at 342.265 140.335 0)
      (effects (font (size 1.27 1.27) (thickness 0.15)) (justify left bottom) hide)
    )
    (property "Manufacturer" "Bourns" (at 352.425 145.415 0)
      (effects (font (size 1.27 1.27) (thickness 0.15)) (justify left bottom) hide)
    )
    (property "MPN" "CR0402-FX-1002GLF" (at 349.885 145.415 0)
      (effects (font (size 1.27 1.27) (thickness 0.15)) (justify left bottom) hide)
    )
    (property "Val" "10k" (at 344.043 144.7799 90)
      (effects (font (size 1.27 1.27) (thickness 0.15)) (justify left))
    )
    (property "License" "Apache-2.0" (at 316.865 160.655 0)
      (effects (font (size 1.27 1.27) (thickness 0.15)) (justify left bottom) hide)
    )
    (property "Author" "Antmicro" (at 314.325 160.655 0)
      (effects (font (size 1.27 1.27) (thickness 0.15)) (justify left bottom) hide)
    )
    (property "Tolerance" "1%" (at 332.105 160.655 0)
      (effects (font (size 1.27 1.27)) (justify left bottom) hide)
    )
    (pin "1")
    (pin "2")
    (instances
      (project "kria-k26-devboard"
        (path ""
          (reference "R114") (unit 1)
        )
      )
    )
  )

  (symbol (lib_id "kria-k26-devboard:GND") (at 317.5 163.83 0) (unit 1)
    (in_bom yes) (on_board yes) (dnp no) (fields_autoplaced)
    (property "Reference" "#PWR0348" (at 317.5 170.18 0)
      (effects (font (size 1.27 1.27)) hide)
    )
    (property "Value" "GND" (at 317.5 168.91 0)
      (effects (font (size 1.27 1.27)))
    )
    (property "Footprint" "" (at 326.39 171.45 0)
      (effects (font (size 1.27 1.27) (thickness 0.15)) (justify left bottom) hide)
    )
    (property "Datasheet" "" (at 326.39 176.53 0)
      (effects (font (size 1.27 1.27) (thickness 0.15)) (justify left bottom) hide)
    )
    (property "Author" "Antmicro" (at 326.39 171.45 0)
      (effects (font (size 1.27 1.27) (thickness 0.15)) (justify left bottom) hide)
    )
    (property "License" "Apache-2.0" (at 326.39 173.99 0)
      (effects (font (size 1.27 1.27) (thickness 0.15)) (justify left bottom) hide)
    )
    (pin "1")
    (instances
      (project "kria-k26-devboard"
        (path ""
          (reference "#PWR0348") (unit 1)
        )
      )
    )
  )

  (symbol (lib_id "kria-k26-devboard:GND") (at 361.315 163.83 0) (mirror y) (unit 1)
    (in_bom yes) (on_board yes) (dnp no) (fields_autoplaced)
    (property "Reference" "#PWR0362" (at 361.315 170.18 0)
      (effects (font (size 1.27 1.27)) hide)
    )
    (property "Value" "GND" (at 358.775 165.0999 0)
      (effects (font (size 1.27 1.27)) (justify left))
    )
    (property "Footprint" "" (at 352.425 171.45 0)
      (effects (font (size 1.27 1.27) (thickness 0.15)) (justify left bottom) hide)
    )
    (property "Datasheet" "" (at 352.425 176.53 0)
      (effects (font (size 1.27 1.27) (thickness 0.15)) (justify left bottom) hide)
    )
    (property "Author" "Antmicro" (at 352.425 171.45 0)
      (effects (font (size 1.27 1.27) (thickness 0.15)) (justify left bottom) hide)
    )
    (property "License" "Apache-2.0" (at 352.425 173.99 0)
      (effects (font (size 1.27 1.27) (thickness 0.15)) (justify left bottom) hide)
    )
    (pin "1")
    (instances
      (project "kria-k26-devboard"
        (path ""
          (reference "#PWR0362") (unit 1)
        )
      )
    )
  )

  (symbol (lib_id "kria-k26-devboard:R_0R_0402") (at 121.92 121.92 0) (unit 1)
    (in_bom no) (on_board yes) (dnp yes)
    (property "Reference" "R101" (at 119.38 120.65 0)
      (effects (font (size 1.524 1.524)))
    )
    (property "Value" "R_0R_0402" (at 121.92 125.73 0)
      (effects (font (size 1.27 1.27) (thickness 0.15)) (justify left bottom) hide)
    )
    (property "Footprint" "kria-k26-devboard-footprints:R_0402_1005Metric" (at 127 116.84 0)
      (effects (font (size 1.27 1.27) (thickness 0.15)) (justify left bottom) hide)
    )
    (property "Datasheet" "https://industrial.panasonic.com/cdbs/www-data/pdf/RDA0000/AOA0000C301.pdf" (at 121.92 121.92 0)
      (effects (font (size 1.27 1.27) (thickness 0.15)) (justify left bottom) hide)
    )
    (property "Manufacturer" "Panasonic" (at 127 111.76 0)
      (effects (font (size 1.27 1.27) (thickness 0.15)) (justify left bottom) hide)
    )
    (property "MPN" "ERJ2GE0R00X" (at 127 114.3 0)
      (effects (font (size 1.27 1.27) (thickness 0.15)) (justify left bottom) hide)
    )
    (property "Val" "0R" (at 128.27 120.65 0)
      (effects (font (size 1.27 1.27) (thickness 0.15)))
    )
    (property "DNP" "DNP" (at 124.46 121.92 0)
      (effects (font (size 1.27 1.27)))
    )
    (property "License" "Apache-2.0" (at 142.24 147.32 0)
      (effects (font (size 1.27 1.27) (thickness 0.15)) (justify left bottom) hide)
    )
    (property "Author" "Antmicro" (at 142.24 149.86 0)
      (effects (font (size 1.27 1.27) (thickness 0.15)) (justify left bottom) hide)
    )
    (property "Tolerance" "~" (at 142.24 132.08 0)
      (effects (font (size 1.27 1.27)) (justify left bottom) hide)
    )
    (property "Current" "1A" (at 142.24 152.4 0)
      (effects (font (size 1.27 1.27) (thickness 0.15)) (justify left bottom) hide)
    )
    (pin "1")
    (pin "2")
    (instances
      (project "kria-k26-devboard"
        (path ""
          (reference "R101") (unit 1)
        )
      )
    )
  )

  (symbol (lib_id "kria-k26-devboard:R_0R_0402") (at 94.615 116.84 0) (unit 1)
    (in_bom yes) (on_board yes) (dnp no)
    (property "Reference" "R97" (at 92.71 115.57 0)
      (effects (font (size 1.524 1.524)))
    )
    (property "Value" "R_0R_0402" (at 94.615 120.65 0)
      (effects (font (size 1.27 1.27) (thickness 0.15)) (justify left bottom) hide)
    )
    (property "Footprint" "kria-k26-devboard-footprints:R_0402_1005Metric" (at 99.695 111.76 0)
      (effects (font (size 1.27 1.27) (thickness 0.15)) (justify left bottom) hide)
    )
    (property "Datasheet" "https://industrial.panasonic.com/cdbs/www-data/pdf/RDA0000/AOA0000C301.pdf" (at 94.615 116.84 0)
      (effects (font (size 1.27 1.27) (thickness 0.15)) (justify left bottom) hide)
    )
    (property "Manufacturer" "Panasonic" (at 99.695 106.68 0)
      (effects (font (size 1.27 1.27) (thickness 0.15)) (justify left bottom) hide)
    )
    (property "MPN" "ERJ2GE0R00X" (at 99.695 109.22 0)
      (effects (font (size 1.27 1.27) (thickness 0.15)) (justify left bottom) hide)
    )
    (property "Val" "0R" (at 100.965 115.57 0)
      (effects (font (size 1.27 1.27) (thickness 0.15)))
    )
    (property "License" "Apache-2.0" (at 114.935 142.24 0)
      (effects (font (size 1.27 1.27) (thickness 0.15)) (justify left bottom) hide)
    )
    (property "Author" "Antmicro" (at 114.935 144.78 0)
      (effects (font (size 1.27 1.27) (thickness 0.15)) (justify left bottom) hide)
    )
    (property "Tolerance" "~" (at 114.935 127 0)
      (effects (font (size 1.27 1.27)) (justify left bottom) hide)
    )
    (property "Current" "1A" (at 114.935 147.32 0)
      (effects (font (size 1.27 1.27) (thickness 0.15)) (justify left bottom) hide)
    )
    (pin "1")
    (pin "2")
    (instances
      (project "kria-k26-devboard"
        (path ""
          (reference "R97") (unit 1)
        )
      )
    )
  )

  (symbol (lib_id "kria-k26-devboard:R_0R_0402") (at 121.92 116.84 0) (unit 1)
    (in_bom no) (on_board yes) (dnp yes)
    (property "Reference" "R100" (at 119.38 115.57 0)
      (effects (font (size 1.524 1.524)))
    )
    (property "Value" "R_0R_0402" (at 121.92 120.65 0)
      (effects (font (size 1.27 1.27) (thickness 0.15)) (justify left bottom) hide)
    )
    (property "Footprint" "kria-k26-devboard-footprints:R_0402_1005Metric" (at 127 111.76 0)
      (effects (font (size 1.27 1.27) (thickness 0.15)) (justify left bottom) hide)
    )
    (property "Datasheet" "https://industrial.panasonic.com/cdbs/www-data/pdf/RDA0000/AOA0000C301.pdf" (at 121.92 116.84 0)
      (effects (font (size 1.27 1.27) (thickness 0.15)) (justify left bottom) hide)
    )
    (property "Manufacturer" "Panasonic" (at 127 106.68 0)
      (effects (font (size 1.27 1.27) (thickness 0.15)) (justify left bottom) hide)
    )
    (property "MPN" "ERJ2GE0R00X" (at 127 109.22 0)
      (effects (font (size 1.27 1.27) (thickness 0.15)) (justify left bottom) hide)
    )
    (property "Val" "0R" (at 128.27 115.57 0)
      (effects (font (size 1.27 1.27) (thickness 0.15)))
    )
    (property "DNP" "DNP" (at 124.46 116.84 0)
      (effects (font (size 1.27 1.27)))
    )
    (property "License" "Apache-2.0" (at 142.24 142.24 0)
      (effects (font (size 1.27 1.27) (thickness 0.15)) (justify left bottom) hide)
    )
    (property "Author" "Antmicro" (at 142.24 144.78 0)
      (effects (font (size 1.27 1.27) (thickness 0.15)) (justify left bottom) hide)
    )
    (property "Tolerance" "~" (at 142.24 127 0)
      (effects (font (size 1.27 1.27)) (justify left bottom) hide)
    )
    (property "Current" "1A" (at 142.24 147.32 0)
      (effects (font (size 1.27 1.27) (thickness 0.15)) (justify left bottom) hide)
    )
    (pin "1")
    (pin "2")
    (instances
      (project "kria-k26-devboard"
        (path ""
          (reference "R100") (unit 1)
        )
      )
    )
  )

  (symbol (lib_id "kria-k26-devboard:R_0R_0402") (at 94.615 121.92 0) (unit 1)
    (in_bom yes) (on_board yes) (dnp no)
    (property "Reference" "R98" (at 92.71 120.65 0)
      (effects (font (size 1.524 1.524)))
    )
    (property "Value" "R_0R_0402" (at 94.615 125.73 0)
      (effects (font (size 1.27 1.27) (thickness 0.15)) (justify left bottom) hide)
    )
    (property "Footprint" "kria-k26-devboard-footprints:R_0402_1005Metric" (at 99.695 116.84 0)
      (effects (font (size 1.27 1.27) (thickness 0.15)) (justify left bottom) hide)
    )
    (property "Datasheet" "https://industrial.panasonic.com/cdbs/www-data/pdf/RDA0000/AOA0000C301.pdf" (at 94.615 121.92 0)
      (effects (font (size 1.27 1.27) (thickness 0.15)) (justify left bottom) hide)
    )
    (property "Manufacturer" "Panasonic" (at 99.695 111.76 0)
      (effects (font (size 1.27 1.27) (thickness 0.15)) (justify left bottom) hide)
    )
    (property "MPN" "ERJ2GE0R00X" (at 99.695 114.3 0)
      (effects (font (size 1.27 1.27) (thickness 0.15)) (justify left bottom) hide)
    )
    (property "Val" "0R" (at 100.965 120.65 0)
      (effects (font (size 1.27 1.27) (thickness 0.15)))
    )
    (property "License" "Apache-2.0" (at 114.935 147.32 0)
      (effects (font (size 1.27 1.27) (thickness 0.15)) (justify left bottom) hide)
    )
    (property "Author" "Antmicro" (at 114.935 149.86 0)
      (effects (font (size 1.27 1.27) (thickness 0.15)) (justify left bottom) hide)
    )
    (property "Tolerance" "~" (at 114.935 132.08 0)
      (effects (font (size 1.27 1.27)) (justify left bottom) hide)
    )
    (property "Current" "1A" (at 114.935 152.4 0)
      (effects (font (size 1.27 1.27) (thickness 0.15)) (justify left bottom) hide)
    )
    (pin "1")
    (pin "2")
    (instances
      (project "kria-k26-devboard"
        (path ""
          (reference "R98") (unit 1)
        )
      )
    )
  )

  (symbol (lib_id "kria-k26-devboard:TPD4E05U06QDQARQ1") (at 257.81 252.095 90) (unit 1)
    (in_bom yes) (on_board yes) (dnp no)
    (property "Reference" "U41" (at 262.89 238.76 90)
      (effects (font (size 1.27 1.27)))
    )
    (property "Value" "TPD4E05U06QDQARQ1" (at 275.59 244.475 0)
      (effects (font (size 1.27 1.27) (thickness 0.15)) hide)
    )
    (property "Footprint" "kria-k26-devboard-footprints:USON-10_2.5x1mm_P0.5mm" (at 246.38 250.825 0)
      (effects (font (size 1.27 1.27) (thickness 0.15)) (justify left bottom) hide)
    )
    (property "Datasheet" "https://www.ti.com/lit/ds/symlink/tpd4e05u06-q1.pdf?HQS=dis-mous-null-mousermode-dsf-pf-null-wwe&ts=1663591265741&ref_url=https%253A%252F%252Fwww.mouser.com%252F" (at 247.65 252.095 0)
      (effects (font (size 1.27 1.27) (thickness 0.15)) (justify left bottom) hide)
    )
    (property "Manufacturer" "Texas Instruments" (at 241.3 243.205 0)
      (effects (font (size 1.27 1.27) (thickness 0.15)) (justify left bottom) hide)
    )
    (property "MPN" "TPD4E05U06QDQARQ1" (at 252.73 241.3 90)
      (effects (font (size 1.27 1.27) (thickness 0.15)) (justify right))
    )
    (property "Author" "Antmicro" (at 273.05 226.695 0)
      (effects (font (size 1.27 1.27) (thickness 0.15)) (justify left bottom) hide)
    )
    (property "License" "Apache-2.0" (at 275.59 226.695 0)
      (effects (font (size 1.27 1.27) (thickness 0.15)) (justify left bottom) hide)
    )
    (pin "1")
    (pin "10")
    (pin "2")
    (pin "3")
    (pin "4")
    (pin "5")
    (pin "6")
    (pin "7")
    (pin "8")
    (pin "9")
    (instances
      (project "kria-k26-devboard"
        (path ""
          (reference "U41") (unit 1)
        )
      )
    )
  )

  (symbol (lib_id "kria-k26-devboard:GND") (at 22.86 109.855 0) (unit 1)
    (in_bom yes) (on_board yes) (dnp no) (fields_autoplaced)
    (property "Reference" "#PWR0180" (at 22.86 116.205 0)
      (effects (font (size 1.27 1.27)) hide)
    )
    (property "Value" "GND" (at 22.86 114.935 0)
      (effects (font (size 1.27 1.27)))
    )
    (property "Footprint" "" (at 31.75 117.475 0)
      (effects (font (size 1.27 1.27) (thickness 0.15)) (justify left bottom) hide)
    )
    (property "Datasheet" "" (at 31.75 122.555 0)
      (effects (font (size 1.27 1.27) (thickness 0.15)) (justify left bottom) hide)
    )
    (property "Author" "Antmicro" (at 31.75 117.475 0)
      (effects (font (size 1.27 1.27) (thickness 0.15)) (justify left bottom) hide)
    )
    (property "License" "Apache-2.0" (at 31.75 120.015 0)
      (effects (font (size 1.27 1.27) (thickness 0.15)) (justify left bottom) hide)
    )
    (pin "1")
    (instances
      (project "kria-k26-devboard"
        (path ""
          (reference "#PWR0180") (unit 1)
        )
      )
    )
  )

  (symbol (lib_id "kria-k26-devboard:SN74AVC2T245_UQFN") (at 298.45 148.59 0) (unit 1)
    (in_bom yes) (on_board yes) (dnp no)
    (property "Reference" "U44" (at 306.705 142.24 0)
      (effects (font (size 1.27 1.27)))
    )
    (property "Value" "SN74AVC2T245_UQFN" (at 306.705 168.91 0)
      (effects (font (size 1.27 1.27) (thickness 0.15)) hide)
    )
    (property "Footprint" "kria-k26-devboard-footprints:UQFN-10_1.4x1.8x0.5mm_P0.4mm" (at 298.45 148.59 0)
      (effects (font (size 1.27 1.27) (thickness 0.15)) (justify left bottom) hide)
    )
    (property "Datasheet" "https://www.ti.com/lit/ds/symlink/sn74avc2t245.pdf?ts=1678888074783&ref_url=https%253A%252F%252Fwww.google.com%252F" (at 298.45 148.59 0)
      (effects (font (size 1.27 1.27) (thickness 0.15)) (justify left bottom) hide)
    )
    (property "Manufacturer" "Texas Instruments" (at 298.45 148.59 0)
      (effects (font (size 1.27 1.27) (thickness 0.15)) (justify left bottom) hide)
    )
    (property "MPN" "SN74AVC2T245RSWR" (at 306.705 144.78 0)
      (effects (font (size 1.27 1.27) (thickness 0.15)))
    )
    (property "Author" "Antmicro" (at 344.17 166.37 0)
      (effects (font (size 1.27 1.27) (thickness 0.15)) (justify left bottom) hide)
    )
    (property "License" "Apache-2.0" (at 344.17 168.91 0)
      (effects (font (size 1.27 1.27) (thickness 0.15)) (justify left bottom) hide)
    )
    (pin "1")
    (pin "10")
    (pin "2")
    (pin "3")
    (pin "4")
    (pin "5")
    (pin "6")
    (pin "7")
    (pin "8")
    (pin "9")
    (instances
      (project "kria-k26-devboard"
        (path ""
          (reference "U44") (unit 1)
        )
      )
    )
  )

  (symbol (lib_id "kria-k26-devboard:R_2k2_0402") (at 171.323 269.24 0) (unit 1)
    (in_bom yes) (on_board yes) (dnp no)
    (property "Reference" "R107" (at 173.863 271.78 0)
      (effects (font (size 1.524 1.524)))
    )
    (property "Value" "R_2k2_0402" (at 171.323 273.05 0)
      (effects (font (size 1.27 1.27) (thickness 0.15)) (justify left bottom) hide)
    )
    (property "Footprint" "kria-k26-devboard-footprints:R_0402_1005Metric" (at 176.403 264.16 0)
      (effects (font (size 1.27 1.27) (thickness 0.15)) (justify left bottom) hide)
    )
    (property "Datasheet" "https://www.bourns.com/docs/product-datasheets/cr.pdf" (at 171.323 269.24 0)
      (effects (font (size 1.27 1.27) (thickness 0.15)) (justify left bottom) hide)
    )
    (property "Manufacturer" "Bourns" (at 176.403 259.08 0)
      (effects (font (size 1.27 1.27) (thickness 0.15)) (justify left bottom) hide)
    )
    (property "MPN" "CR0402-FX-2201GLF" (at 176.403 261.62 0)
      (effects (font (size 1.27 1.27) (thickness 0.15)) (justify left bottom) hide)
    )
    (property "Val" "2k2" (at 173.863 274.32 0)
      (effects (font (size 1.27 1.27) (thickness 0.15)))
    )
    (property "License" "Apache-2.0" (at 191.643 294.64 0)
      (effects (font (size 1.27 1.27) (thickness 0.15)) (justify left bottom) hide)
    )
    (property "Author" "Antmicro" (at 191.643 297.18 0)
      (effects (font (size 1.27 1.27) (thickness 0.15)) (justify left bottom) hide)
    )
    (property "Tolerance" "1%" (at 191.643 279.4 0)
      (effects (font (size 1.27 1.27)) (justify left bottom) hide)
    )
    (pin "1")
    (pin "2")
    (instances
      (project "kria-k26-devboard"
        (path ""
          (reference "R107") (unit 1)
        )
      )
    )
  )

  (symbol (lib_id "kria-k26-devboard:C_1u_0402") (at 123.19 36.83 270) (unit 1)
    (in_bom yes) (on_board yes) (dnp no) (fields_autoplaced)
    (property "Reference" "C243" (at 125.73 38.1063 90)
      (effects (font (size 1.524 1.524)) (justify left))
    )
    (property "Value" "C_1u_0402" (at 119.38 36.83 0)
      (effects (font (size 1.27 1.27) (thickness 0.15)) (justify left bottom) hide)
    )
    (property "Footprint" "kria-k26-devboard-footprints:C_0402_1005Metric" (at 128.27 41.91 0)
      (effects (font (size 1.27 1.27) (thickness 0.15)) (justify left bottom) hide)
    )
    (property "Datasheet" " " (at 123.19 36.83 0)
      (effects (font (size 1.27 1.27) (thickness 0.15)) (justify left bottom) hide)
    )
    (property "Manufacturer" "TDK" (at 133.35 41.91 0)
      (effects (font (size 1.27 1.27) (thickness 0.15)) (justify left bottom) hide)
    )
    (property "MPN" "C1005X6S1A105K050BC" (at 130.81 41.91 0)
      (effects (font (size 1.27 1.27) (thickness 0.15)) (justify left bottom) hide)
    )
    (property "Val" "1u" (at 125.73 41.2812 90)
      (effects (font (size 1.27 1.27) (thickness 0.15)) (justify left))
    )
    (property "License" "Apache-2.0" (at 100.33 57.15 0)
      (effects (font (size 1.27 1.27) (thickness 0.15)) (justify left bottom) hide)
    )
    (property "Author" "Antmicro" (at 97.79 57.15 0)
      (effects (font (size 1.27 1.27) (thickness 0.15)) (justify left bottom) hide)
    )
    (property "Voltage" "" (at 95.25 57.15 0)
      (effects (font (size 1.27 1.27)) (justify left bottom) hide)
    )
    (property "Dielectric" "" (at 92.71 57.15 0)
      (effects (font (size 1.27 1.27)) (justify left bottom) hide)
    )
    (pin "1")
    (pin "2")
    (instances
      (project "kria-k26-devboard"
        (path ""
          (reference "C243") (unit 1)
        )
      )
    )
  )

  (symbol (lib_id "kria-k26-devboard:R_5k11_0402") (at 41.275 43.18 0) (unit 1)
    (in_bom yes) (on_board yes) (dnp no)
    (property "Reference" "R167" (at 38.735 41.91 0)
      (effects (font (size 1.524 1.524)))
    )
    (property "Value" "R_5k11_0402" (at 41.275 46.99 0)
      (effects (font (size 1.27 1.27) (thickness 0.15)) (justify left bottom) hide)
    )
    (property "Footprint" "kria-k26-devboard-footprints:R_0402_1005Metric" (at 46.355 38.1 0)
      (effects (font (size 1.27 1.27) (thickness 0.15)) (justify left bottom) hide)
    )
    (property "Datasheet" "https://www.bourns.com/docs/product-datasheets/cr.pdf" (at 41.275 43.18 0)
      (effects (font (size 1.27 1.27) (thickness 0.15)) (justify left bottom) hide)
    )
    (property "Manufacturer" "Bourns" (at 46.355 33.02 0)
      (effects (font (size 1.27 1.27) (thickness 0.15)) (justify left bottom) hide)
    )
    (property "MPN" "CR0402-FX-5111GLF" (at 46.355 35.56 0)
      (effects (font (size 1.27 1.27) (thickness 0.15)) (justify left bottom) hide)
    )
    (property "Val" "5k11" (at 48.26 41.91 0)
      (effects (font (size 1.27 1.27) (thickness 0.15)))
    )
    (property "License" "Apache-2.0" (at 61.595 68.58 0)
      (effects (font (size 1.27 1.27) (thickness 0.15)) (justify left bottom) hide)
    )
    (property "Author" "Antmicro" (at 61.595 71.12 0)
      (effects (font (size 1.27 1.27) (thickness 0.15)) (justify left bottom) hide)
    )
    (property "Tolerance" "1%" (at 61.595 53.34 0)
      (effects (font (size 1.27 1.27)) (justify left bottom) hide)
    )
    (pin "1")
    (pin "2")
    (instances
      (project "kria-k26-devboard"
        (path ""
          (reference "R167") (unit 1)
        )
      )
    )
  )

  (symbol (lib_id "kria-k26-devboard:GND") (at 123.19 41.91 0) (unit 1)
    (in_bom yes) (on_board yes) (dnp no) (fields_autoplaced)
    (property "Reference" "#PWR0331" (at 123.19 48.26 0)
      (effects (font (size 1.27 1.27)) hide)
    )
    (property "Value" "GND" (at 123.19 46.99 0)
      (effects (font (size 1.27 1.27)))
    )
    (property "Footprint" "" (at 132.08 49.53 0)
      (effects (font (size 1.27 1.27) (thickness 0.15)) (justify left bottom) hide)
    )
    (property "Datasheet" "" (at 132.08 54.61 0)
      (effects (font (size 1.27 1.27) (thickness 0.15)) (justify left bottom) hide)
    )
    (property "Author" "Antmicro" (at 132.08 49.53 0)
      (effects (font (size 1.27 1.27) (thickness 0.15)) (justify left bottom) hide)
    )
    (property "License" "Apache-2.0" (at 132.08 52.07 0)
      (effects (font (size 1.27 1.27) (thickness 0.15)) (justify left bottom) hide)
    )
    (pin "1")
    (instances
      (project "kria-k26-devboard"
        (path ""
          (reference "#PWR0331") (unit 1)
        )
      )
    )
  )

  (symbol (lib_id "kria-k26-devboard:GND") (at 45.72 109.855 0) (unit 1)
    (in_bom yes) (on_board yes) (dnp no) (fields_autoplaced)
    (property "Reference" "#PWR0181" (at 45.72 116.205 0)
      (effects (font (size 1.27 1.27)) hide)
    )
    (property "Value" "GND" (at 45.72 114.935 0)
      (effects (font (size 1.27 1.27)))
    )
    (property "Footprint" "" (at 54.61 117.475 0)
      (effects (font (size 1.27 1.27) (thickness 0.15)) (justify left bottom) hide)
    )
    (property "Datasheet" "" (at 54.61 122.555 0)
      (effects (font (size 1.27 1.27) (thickness 0.15)) (justify left bottom) hide)
    )
    (property "Author" "Antmicro" (at 54.61 117.475 0)
      (effects (font (size 1.27 1.27) (thickness 0.15)) (justify left bottom) hide)
    )
    (property "License" "Apache-2.0" (at 54.61 120.015 0)
      (effects (font (size 1.27 1.27) (thickness 0.15)) (justify left bottom) hide)
    )
    (pin "1")
    (instances
      (project "kria-k26-devboard"
        (path ""
          (reference "#PWR0181") (unit 1)
        )
      )
    )
  )

  (symbol (lib_id "kria-k26-devboard:GND") (at 30.48 109.855 0) (unit 1)
    (in_bom yes) (on_board yes) (dnp no) (fields_autoplaced)
    (property "Reference" "#PWR0179" (at 30.48 116.205 0)
      (effects (font (size 1.27 1.27)) hide)
    )
    (property "Value" "GND" (at 30.48 114.935 0)
      (effects (font (size 1.27 1.27)))
    )
    (property "Footprint" "" (at 39.37 117.475 0)
      (effects (font (size 1.27 1.27) (thickness 0.15)) (justify left bottom) hide)
    )
    (property "Datasheet" "" (at 39.37 122.555 0)
      (effects (font (size 1.27 1.27) (thickness 0.15)) (justify left bottom) hide)
    )
    (property "Author" "Antmicro" (at 39.37 117.475 0)
      (effects (font (size 1.27 1.27) (thickness 0.15)) (justify left bottom) hide)
    )
    (property "License" "Apache-2.0" (at 39.37 120.015 0)
      (effects (font (size 1.27 1.27) (thickness 0.15)) (justify left bottom) hide)
    )
    (pin "1")
    (instances
      (project "kria-k26-devboard"
        (path ""
          (reference "#PWR0179") (unit 1)
        )
      )
    )
  )

  (symbol (lib_id "kria-k26-devboard:GND") (at 102.235 64.135 0) (unit 1)
    (in_bom yes) (on_board yes) (dnp no) (fields_autoplaced)
    (property "Reference" "#PWR0182" (at 102.235 70.485 0)
      (effects (font (size 1.27 1.27)) hide)
    )
    (property "Value" "GND" (at 102.235 68.58 0)
      (effects (font (size 1.27 1.27)))
    )
    (property "Footprint" "" (at 111.125 71.755 0)
      (effects (font (size 1.27 1.27) (thickness 0.15)) (justify left bottom) hide)
    )
    (property "Datasheet" "" (at 111.125 76.835 0)
      (effects (font (size 1.27 1.27) (thickness 0.15)) (justify left bottom) hide)
    )
    (property "Author" "Antmicro" (at 111.125 71.755 0)
      (effects (font (size 1.27 1.27) (thickness 0.15)) (justify left bottom) hide)
    )
    (property "License" "Apache-2.0" (at 111.125 74.295 0)
      (effects (font (size 1.27 1.27) (thickness 0.15)) (justify left bottom) hide)
    )
    (pin "1")
    (instances
      (project "kria-k26-devboard"
        (path ""
          (reference "#PWR0182") (unit 1)
        )
      )
    )
  )

  (symbol (lib_id "kria-k26-devboard:GND") (at 316.865 200.66 0) (mirror y) (unit 1)
    (in_bom yes) (on_board yes) (dnp no) (fields_autoplaced)
    (property "Reference" "#PWR03" (at 316.865 207.01 0)
      (effects (font (size 1.27 1.27)) hide)
    )
    (property "Value" "GND" (at 316.865 205.74 0)
      (effects (font (size 1.27 1.27)))
    )
    (property "Footprint" "" (at 307.975 208.28 0)
      (effects (font (size 1.27 1.27) (thickness 0.15)) (justify left bottom) hide)
    )
    (property "Datasheet" "" (at 307.975 213.36 0)
      (effects (font (size 1.27 1.27) (thickness 0.15)) (justify left bottom) hide)
    )
    (property "Author" "Antmicro" (at 307.975 208.28 0)
      (effects (font (size 1.27 1.27) (thickness 0.15)) (justify left bottom) hide)
    )
    (property "License" "Apache-2.0" (at 307.975 210.82 0)
      (effects (font (size 1.27 1.27) (thickness 0.15)) (justify left bottom) hide)
    )
    (pin "1")
    (instances
      (project "kria-k26-devboard"
        (path ""
          (reference "#PWR03") (unit 1)
        )
      )
    )
  )

  (symbol (lib_id "kria-k26-devboard:GND") (at 102.235 41.91 0) (unit 1)
    (in_bom yes) (on_board yes) (dnp no) (fields_autoplaced)
    (property "Reference" "#PWR0183" (at 102.235 48.26 0)
      (effects (font (size 1.27 1.27)) hide)
    )
    (property "Value" "GND" (at 102.235 46.355 0)
      (effects (font (size 1.27 1.27)))
    )
    (property "Footprint" "" (at 111.125 49.53 0)
      (effects (font (size 1.27 1.27) (thickness 0.15)) (justify left bottom) hide)
    )
    (property "Datasheet" "" (at 111.125 54.61 0)
      (effects (font (size 1.27 1.27) (thickness 0.15)) (justify left bottom) hide)
    )
    (property "Author" "Antmicro" (at 111.125 49.53 0)
      (effects (font (size 1.27 1.27) (thickness 0.15)) (justify left bottom) hide)
    )
    (property "License" "Apache-2.0" (at 111.125 52.07 0)
      (effects (font (size 1.27 1.27) (thickness 0.15)) (justify left bottom) hide)
    )
    (pin "1")
    (instances
      (project "kria-k26-devboard"
        (path ""
          (reference "#PWR0183") (unit 1)
        )
      )
    )
  )

  (symbol (lib_id "kria-k26-devboard:SN74AVC2T245_UQFN") (at 297.815 184.15 0) (unit 1)
    (in_bom yes) (on_board yes) (dnp no)
    (property "Reference" "U45" (at 306.07 177.8 0)
      (effects (font (size 1.27 1.27)))
    )
    (property "Value" "SN74AVC2T245_UQFN" (at 306.07 179.07 0)
      (effects (font (size 1.27 1.27) (thickness 0.15)) hide)
    )
    (property "Footprint" "kria-k26-devboard-footprints:UQFN-10_1.4x1.8x0.5mm_P0.4mm" (at 297.815 184.15 0)
      (effects (font (size 1.27 1.27) (thickness 0.15)) (justify left bottom) hide)
    )
    (property "Datasheet" "https://www.ti.com/lit/ds/symlink/sn74avc2t245.pdf?ts=1678888074783&ref_url=https%253A%252F%252Fwww.google.com%252F" (at 297.815 184.15 0)
      (effects (font (size 1.27 1.27) (thickness 0.15)) (justify left bottom) hide)
    )
    (property "Manufacturer" "Texas Instruments" (at 297.815 184.15 0)
      (effects (font (size 1.27 1.27) (thickness 0.15)) (justify left bottom) hide)
    )
    (property "MPN" "SN74AVC2T245RSWR" (at 306.07 180.34 0)
      (effects (font (size 1.27 1.27) (thickness 0.15)))
    )
    (property "Author" "Antmicro" (at 343.535 201.93 0)
      (effects (font (size 1.27 1.27) (thickness 0.15)) (justify left bottom) hide)
    )
    (property "License" "Apache-2.0" (at 343.535 204.47 0)
      (effects (font (size 1.27 1.27) (thickness 0.15)) (justify left bottom) hide)
    )
    (pin "1")
    (pin "10")
    (pin "2")
    (pin "3")
    (pin "4")
    (pin "5")
    (pin "6")
    (pin "7")
    (pin "8")
    (pin "9")
    (instances
      (project "kria-k26-devboard"
        (path ""
          (reference "U45") (unit 1)
        )
      )
    )
  )

  (symbol (lib_id "kria-k26-devboard:TP_0.75mm_SMD") (at 247.65 158.75 0) (unit 1)
    (in_bom yes) (on_board yes) (dnp no) (fields_autoplaced)
    (property "Reference" "TP63" (at 252.73 158.7499 0)
      (effects (font (size 1.27 1.27)) (justify left))
    )
    (property "Value" "TP_0.75mm_SMD" (at 247.65 161.29 0)
      (effects (font (size 1.27 1.27) (thickness 0.15)) (justify left bottom) hide)
    )
    (property "Footprint" "kria-k26-devboard-footprints:TP_SMD_0.75mm" (at 252.73 153.67 0)
      (effects (font (size 1.27 1.27) (thickness 0.15)) (justify left bottom) hide)
    )
    (property "Datasheet" "" (at 252.73 151.13 0)
      (effects (font (size 1.27 1.27) (thickness 0.15)) (justify left bottom) hide)
    )
    (property "MPN" "" (at 247.65 158.75 0)
      (effects (font (size 1.27 1.27) (thickness 0.15)) (justify left bottom) hide)
    )
    (property "Manufacturer" "" (at 247.65 158.75 0)
      (effects (font (size 1.27 1.27) (thickness 0.15)) (justify left bottom) hide)
    )
    (property "Author" "Antmicro" (at 262.89 173.99 0)
      (effects (font (size 1.27 1.27) (thickness 0.15)) (justify left bottom) hide)
    )
    (property "License" "Apache-2.0" (at 262.89 176.53 0)
      (effects (font (size 1.27 1.27) (thickness 0.15)) (justify left bottom) hide)
    )
    (pin "1")
    (instances
      (project "kria-k26-devboard"
        (path ""
          (reference "TP63") (unit 1)
        )
      )
    )
  )

  (symbol (lib_id "kria-k26-devboard:GND") (at 45.72 129.54 0) (unit 1)
    (in_bom yes) (on_board yes) (dnp no) (fields_autoplaced)
    (property "Reference" "#PWR0175" (at 45.72 135.89 0)
      (effects (font (size 1.27 1.27)) hide)
    )
    (property "Value" "GND" (at 45.72 134.62 0)
      (effects (font (size 1.27 1.27)))
    )
    (property "Footprint" "" (at 54.61 137.16 0)
      (effects (font (size 1.27 1.27) (thickness 0.15)) (justify left bottom) hide)
    )
    (property "Datasheet" "" (at 54.61 142.24 0)
      (effects (font (size 1.27 1.27) (thickness 0.15)) (justify left bottom) hide)
    )
    (property "Author" "Antmicro" (at 54.61 137.16 0)
      (effects (font (size 1.27 1.27) (thickness 0.15)) (justify left bottom) hide)
    )
    (property "License" "Apache-2.0" (at 54.61 139.7 0)
      (effects (font (size 1.27 1.27) (thickness 0.15)) (justify left bottom) hide)
    )
    (pin "1")
    (instances
      (project "kria-k26-devboard"
        (path ""
          (reference "#PWR0175") (unit 1)
        )
      )
    )
  )

  (symbol (lib_id "kria-k26-devboard:GND") (at 30.48 129.54 0) (unit 1)
    (in_bom yes) (on_board yes) (dnp no) (fields_autoplaced)
    (property "Reference" "#PWR0173" (at 30.48 135.89 0)
      (effects (font (size 1.27 1.27)) hide)
    )
    (property "Value" "GND" (at 30.48 134.62 0)
      (effects (font (size 1.27 1.27)))
    )
    (property "Footprint" "" (at 39.37 137.16 0)
      (effects (font (size 1.27 1.27) (thickness 0.15)) (justify left bottom) hide)
    )
    (property "Datasheet" "" (at 39.37 142.24 0)
      (effects (font (size 1.27 1.27) (thickness 0.15)) (justify left bottom) hide)
    )
    (property "Author" "Antmicro" (at 39.37 137.16 0)
      (effects (font (size 1.27 1.27) (thickness 0.15)) (justify left bottom) hide)
    )
    (property "License" "Apache-2.0" (at 39.37 139.7 0)
      (effects (font (size 1.27 1.27) (thickness 0.15)) (justify left bottom) hide)
    )
    (pin "1")
    (instances
      (project "kria-k26-devboard"
        (path ""
          (reference "#PWR0173") (unit 1)
        )
      )
    )
  )

  (symbol (lib_id "kria-k26-devboard:C_1u_25V_0603") (at 93.98 59.055 270) (unit 1)
    (in_bom yes) (on_board yes) (dnp no) (fields_autoplaced)
    (property "Reference" "C155" (at 90.805 60.3313 90)
      (effects (font (size 1.524 1.524)) (justify right))
    )
    (property "Value" "C_1u_25V_0603" (at 90.17 59.055 0)
      (effects (font (size 1.27 1.27) (thickness 0.15)) (justify left bottom) hide)
    )
    (property "Footprint" "kria-k26-devboard-footprints:C_0603_1608Metric" (at 99.06 64.135 0)
      (effects (font (size 1.27 1.27) (thickness 0.15)) (justify left bottom) hide)
    )
    (property "Datasheet" " " (at 93.98 59.055 0)
      (effects (font (size 1.27 1.27) (thickness 0.15)) (justify left bottom) hide)
    )
    (property "Manufacturer" "Samsung" (at 104.14 64.135 0)
      (effects (font (size 1.27 1.27) (thickness 0.15)) (justify left bottom) hide)
    )
    (property "MPN" "CL10A105KA8NNNC" (at 101.6 64.135 0)
      (effects (font (size 1.27 1.27) (thickness 0.15)) (justify left bottom) hide)
    )
    (property "Val" "1u/25V" (at 90.805 63.5062 90)
      (effects (font (size 1.27 1.27) (thickness 0.15)) (justify right))
    )
    (property "License" "Apache-2.0" (at 71.12 79.375 0)
      (effects (font (size 1.27 1.27) (thickness 0.15)) (justify left bottom) hide)
    )
    (property "Author" "Antmicro" (at 68.58 79.375 0)
      (effects (font (size 1.27 1.27) (thickness 0.15)) (justify left bottom) hide)
    )
    (property "Voltage" "" (at 66.04 79.375 0)
      (effects (font (size 1.27 1.27)) (justify left bottom) hide)
    )
    (property "Dielectric" "" (at 63.5 79.375 0)
      (effects (font (size 1.27 1.27)) (justify left bottom) hide)
    )
    (pin "1")
    (pin "2")
    (instances
      (project "kria-k26-devboard"
        (path ""
          (reference "C155") (unit 1)
        )
      )
    )
  )

  (symbol (lib_id "kria-k26-devboard:93LC66BT_DFN") (at 144.78 261.62 0) (unit 1)
    (in_bom yes) (on_board yes) (dnp no) (fields_autoplaced)
    (property "Reference" "U39" (at 154.94 254 0)
      (effects (font (size 1.27 1.27)))
    )
    (property "Value" "93LC66BT_DFN" (at 180.34 266.7 0)
      (effects (font (size 1.27 1.27) (thickness 0.15)) (justify left bottom) hide)
    )
    (property "Footprint" "kria-k26-devboard-footprints:DFN-8-1EP_3x2mm_P0.5mm_EP1.36x1.46mm" (at 180.34 269.24 0)
      (effects (font (size 1.27 1.27) (thickness 0.15)) (justify left bottom) hide)
    )
    (property "Datasheet" "https://www.mouser.com/datasheet/2/268/21795C-64371.pdf" (at 180.34 271.78 0)
      (effects (font (size 1.27 1.27) (thickness 0.15)) (justify left bottom) hide)
    )
    (property "MPN" "93LC66BT-I/MC" (at 154.94 256.54 0)
      (effects (font (size 1.27 1.27)))
    )
    (property "Manufacturer" "Microchip Technology" (at 180.34 278.13 0)
      (effects (font (size 1.27 1.27)) (justify left) hide)
    )
    (property "Author" "Antmicro" (at 180.34 274.32 0)
      (effects (font (size 1.27 1.27) (thickness 0.15)) (justify left bottom) hide)
    )
    (property "License" "Apache-2.0" (at 180.34 276.86 0)
      (effects (font (size 1.27 1.27) (thickness 0.15)) (justify left bottom) hide)
    )
    (pin "1")
    (pin "2")
    (pin "3")
    (pin "4")
    (pin "5")
    (pin "6")
    (pin "7")
    (pin "8")
    (pin "9")
    (instances
      (project "kria-k26-devboard"
        (path ""
          (reference "U39") (unit 1)
        )
      )
    )
  )

  (symbol (lib_id "kria-k26-devboard:NCP730BMT330_WSON") (at 103.505 57.15 0) (unit 1)
    (in_bom yes) (on_board yes) (dnp no)
    (property "Reference" "U38" (at 111.125 50.165 0)
      (effects (font (size 1.27 1.27)))
    )
    (property "Value" "NCP730BMT330_WSON" (at 111.125 52.07 0)
      (effects (font (size 1.27 1.27) (thickness 0.15)) (justify left bottom) hide)
    )
    (property "Footprint" "kria-k26-devboard-footprints:WSON-6-1EP_2x2mm_P0.65mm" (at 102.235 73.66 0)
      (effects (font (size 1.27 1.27) (thickness 0.15)) (justify left bottom) hide)
    )
    (property "Datasheet" "https://www.onsemi.com/download/data-sheet/pdf/ncp730-d.pdf" (at 102.235 66.04 0)
      (effects (font (size 1.27 1.27) (thickness 0.15)) (justify left bottom) hide)
    )
    (property "MPN" "NCP730BMT330TBG" (at 111.125 52.705 0)
      (effects (font (size 1.27 1.27) (thickness 0.15)))
    )
    (property "Manufacturer" "ON Semiconductor" (at 102.235 68.58 0)
      (effects (font (size 1.27 1.27) (thickness 0.15)) (justify left bottom) hide)
    )
    (property "Author" "Antmicro" (at 133.985 74.93 0)
      (effects (font (size 1.27 1.27) (thickness 0.15)) (justify left bottom) hide)
    )
    (property "License" "Apache-2.0" (at 133.985 77.47 0)
      (effects (font (size 1.27 1.27) (thickness 0.15)) (justify left bottom) hide)
    )
    (pin "1")
    (pin "2")
    (pin "3")
    (pin "4")
    (pin "5")
    (pin "6")
    (pin "7")
    (instances
      (project "kria-k26-devboard"
        (path ""
          (reference "U38") (unit 1)
        )
      )
    )
  )

  (symbol (lib_id "kria-k26-devboard:GND") (at 165.735 61.595 0) (unit 1)
    (in_bom yes) (on_board yes) (dnp no) (fields_autoplaced)
    (property "Reference" "#PWR0177" (at 165.735 67.945 0)
      (effects (font (size 1.27 1.27)) hide)
    )
    (property "Value" "GND" (at 165.735 66.675 0)
      (effects (font (size 1.27 1.27)))
    )
    (property "Footprint" "" (at 174.625 69.215 0)
      (effects (font (size 1.27 1.27) (thickness 0.15)) (justify left bottom) hide)
    )
    (property "Datasheet" "" (at 174.625 74.295 0)
      (effects (font (size 1.27 1.27) (thickness 0.15)) (justify left bottom) hide)
    )
    (property "Author" "Antmicro" (at 174.625 69.215 0)
      (effects (font (size 1.27 1.27) (thickness 0.15)) (justify left bottom) hide)
    )
    (property "License" "Apache-2.0" (at 174.625 71.755 0)
      (effects (font (size 1.27 1.27) (thickness 0.15)) (justify left bottom) hide)
    )
    (pin "1")
    (instances
      (project "kria-k26-devboard"
        (path ""
          (reference "#PWR0177") (unit 1)
        )
      )
    )
  )

  (symbol (lib_id "kria-k26-devboard:GND") (at 38.1 129.54 0) (unit 1)
    (in_bom yes) (on_board yes) (dnp no) (fields_autoplaced)
    (property "Reference" "#PWR0174" (at 38.1 135.89 0)
      (effects (font (size 1.27 1.27)) hide)
    )
    (property "Value" "GND" (at 38.1 134.62 0)
      (effects (font (size 1.27 1.27)))
    )
    (property "Footprint" "" (at 46.99 137.16 0)
      (effects (font (size 1.27 1.27) (thickness 0.15)) (justify left bottom) hide)
    )
    (property "Datasheet" "" (at 46.99 142.24 0)
      (effects (font (size 1.27 1.27) (thickness 0.15)) (justify left bottom) hide)
    )
    (property "Author" "Antmicro" (at 46.99 137.16 0)
      (effects (font (size 1.27 1.27) (thickness 0.15)) (justify left bottom) hide)
    )
    (property "License" "Apache-2.0" (at 46.99 139.7 0)
      (effects (font (size 1.27 1.27) (thickness 0.15)) (justify left bottom) hide)
    )
    (pin "1")
    (instances
      (project "kria-k26-devboard"
        (path ""
          (reference "#PWR0174") (unit 1)
        )
      )
    )
  )

  (symbol (lib_id "kria-k26-devboard:C_4u7_0402") (at 60.96 124.46 270) (unit 1)
    (in_bom yes) (on_board yes) (dnp no)
    (property "Reference" "C242" (at 61.595 125.095 90)
      (effects (font (size 1.524 1.524)) (justify left))
    )
    (property "Value" "C_4u7_0402" (at 57.15 124.46 0)
      (effects (font (size 1.27 1.27) (thickness 0.15)) (justify left bottom) hide)
    )
    (property "Footprint" "kria-k26-devboard-footprints:C_0402_1005Metric" (at 66.04 129.54 0)
      (effects (font (size 1.27 1.27) (thickness 0.15)) (justify left bottom) hide)
    )
    (property "Datasheet" " " (at 60.96 124.46 0)
      (effects (font (size 1.27 1.27) (thickness 0.15)) (justify left bottom) hide)
    )
    (property "Manufacturer" "Murata" (at 71.12 129.54 0)
      (effects (font (size 1.27 1.27) (thickness 0.15)) (justify left bottom) hide)
    )
    (property "MPN" "GRM155R61A475MEAAD" (at 68.58 129.54 0)
      (effects (font (size 1.27 1.27) (thickness 0.15)) (justify left bottom) hide)
    )
    (property "Val" "4u7" (at 61.595 128.905 90)
      (effects (font (size 1.27 1.27) (thickness 0.15)) (justify left))
    )
    (property "License" "Apache-2.0" (at 38.1 144.78 0)
      (effects (font (size 1.27 1.27) (thickness 0.15)) (justify left bottom) hide)
    )
    (property "Author" "Antmicro" (at 35.56 144.78 0)
      (effects (font (size 1.27 1.27) (thickness 0.15)) (justify left bottom) hide)
    )
    (property "Voltage" "" (at 33.02 144.78 0)
      (effects (font (size 1.27 1.27)) (justify left bottom) hide)
    )
    (property "Dielectric" "" (at 30.48 144.78 0)
      (effects (font (size 1.27 1.27)) (justify left bottom) hide)
    )
    (pin "1")
    (pin "2")
    (instances
      (project "kria-k26-devboard"
        (path ""
          (reference "C242") (unit 1)
        )
      )
    )
  )

  (symbol (lib_id "kria-k26-devboard:GND") (at 22.86 129.54 0) (unit 1)
    (in_bom yes) (on_board yes) (dnp no) (fields_autoplaced)
    (property "Reference" "#PWR0172" (at 22.86 135.89 0)
      (effects (font (size 1.27 1.27)) hide)
    )
    (property "Value" "GND" (at 22.86 134.62 0)
      (effects (font (size 1.27 1.27)))
    )
    (property "Footprint" "" (at 31.75 137.16 0)
      (effects (font (size 1.27 1.27) (thickness 0.15)) (justify left bottom) hide)
    )
    (property "Datasheet" "" (at 31.75 142.24 0)
      (effects (font (size 1.27 1.27) (thickness 0.15)) (justify left bottom) hide)
    )
    (property "Author" "Antmicro" (at 31.75 137.16 0)
      (effects (font (size 1.27 1.27) (thickness 0.15)) (justify left bottom) hide)
    )
    (property "License" "Apache-2.0" (at 31.75 139.7 0)
      (effects (font (size 1.27 1.27) (thickness 0.15)) (justify left bottom) hide)
    )
    (pin "1")
    (instances
      (project "kria-k26-devboard"
        (path ""
          (reference "#PWR0172") (unit 1)
        )
      )
    )
  )

  (symbol (lib_id "kria-k26-devboard:NCP730BMT330_WSON") (at 103.505 34.925 0) (unit 1)
    (in_bom yes) (on_board yes) (dnp no)
    (property "Reference" "U61" (at 111.125 27.94 0)
      (effects (font (size 1.27 1.27)))
    )
    (property "Value" "NCP730BMT330_WSON" (at 111.125 29.845 0)
      (effects (font (size 1.27 1.27) (thickness 0.15)) (justify left bottom) hide)
    )
    (property "Footprint" "kria-k26-devboard-footprints:WSON-6-1EP_2x2mm_P0.65mm" (at 102.235 51.435 0)
      (effects (font (size 1.27 1.27) (thickness 0.15)) (justify left bottom) hide)
    )
    (property "Datasheet" "https://www.onsemi.com/download/data-sheet/pdf/ncp730-d.pdf" (at 102.235 43.815 0)
      (effects (font (size 1.27 1.27) (thickness 0.15)) (justify left bottom) hide)
    )
    (property "MPN" "NCP730BMT330TBG" (at 111.125 30.48 0)
      (effects (font (size 1.27 1.27) (thickness 0.15)))
    )
    (property "Manufacturer" "ON Semiconductor" (at 102.235 46.355 0)
      (effects (font (size 1.27 1.27) (thickness 0.15)) (justify left bottom) hide)
    )
    (property "Author" "Antmicro" (at 133.985 52.705 0)
      (effects (font (size 1.27 1.27) (thickness 0.15)) (justify left bottom) hide)
    )
    (property "License" "Apache-2.0" (at 133.985 55.245 0)
      (effects (font (size 1.27 1.27) (thickness 0.15)) (justify left bottom) hide)
    )
    (pin "1")
    (pin "2")
    (pin "3")
    (pin "4")
    (pin "5")
    (pin "6")
    (pin "7")
    (instances
      (project "kria-k26-devboard"
        (path ""
          (reference "U61") (unit 1)
        )
      )
    )
  )

  (symbol (lib_id "kria-k26-devboard:GND") (at 97.79 41.91 0) (unit 1)
    (in_bom yes) (on_board yes) (dnp no) (fields_autoplaced)
    (property "Reference" "#PWR0412" (at 97.79 48.26 0)
      (effects (font (size 1.27 1.27)) hide)
    )
    (property "Value" "GND" (at 97.79 46.355 0)
      (effects (font (size 1.27 1.27)))
    )
    (property "Footprint" "" (at 106.68 49.53 0)
      (effects (font (size 1.27 1.27) (thickness 0.15)) (justify left bottom) hide)
    )
    (property "Datasheet" "" (at 106.68 54.61 0)
      (effects (font (size 1.27 1.27) (thickness 0.15)) (justify left bottom) hide)
    )
    (property "Author" "Antmicro" (at 106.68 49.53 0)
      (effects (font (size 1.27 1.27) (thickness 0.15)) (justify left bottom) hide)
    )
    (property "License" "Apache-2.0" (at 106.68 52.07 0)
      (effects (font (size 1.27 1.27) (thickness 0.15)) (justify left bottom) hide)
    )
    (pin "1")
    (instances
      (project "kria-k26-devboard"
        (path ""
          (reference "#PWR0412") (unit 1)
        )
      )
    )
  )

  (symbol (lib_id "kria-k26-devboard:C_1u_0402") (at 123.19 59.055 270) (unit 1)
    (in_bom yes) (on_board yes) (dnp no) (fields_autoplaced)
    (property "Reference" "C159" (at 126.365 60.3313 90)
      (effects (font (size 1.524 1.524)) (justify left))
    )
    (property "Value" "C_1u_0402" (at 119.38 59.055 0)
      (effects (font (size 1.27 1.27) (thickness 0.15)) (justify left bottom) hide)
    )
    (property "Footprint" "kria-k26-devboard-footprints:C_0402_1005Metric" (at 128.27 64.135 0)
      (effects (font (size 1.27 1.27) (thickness 0.15)) (justify left bottom) hide)
    )
    (property "Datasheet" " " (at 123.19 59.055 0)
      (effects (font (size 1.27 1.27) (thickness 0.15)) (justify left bottom) hide)
    )
    (property "Manufacturer" "TDK" (at 133.35 64.135 0)
      (effects (font (size 1.27 1.27) (thickness 0.15)) (justify left bottom) hide)
    )
    (property "MPN" "C1005X6S1A105K050BC" (at 130.81 64.135 0)
      (effects (font (size 1.27 1.27) (thickness 0.15)) (justify left bottom) hide)
    )
    (property "Val" "1u" (at 126.365 63.5062 90)
      (effects (font (size 1.27 1.27) (thickness 0.15)) (justify left))
    )
    (property "License" "Apache-2.0" (at 100.33 79.375 0)
      (effects (font (size 1.27 1.27) (thickness 0.15)) (justify left bottom) hide)
    )
    (property "Author" "Antmicro" (at 97.79 79.375 0)
      (effects (font (size 1.27 1.27) (thickness 0.15)) (justify left bottom) hide)
    )
    (property "Voltage" "" (at 95.25 79.375 0)
      (effects (font (size 1.27 1.27)) (justify left bottom) hide)
    )
    (property "Dielectric" "" (at 92.71 79.375 0)
      (effects (font (size 1.27 1.27)) (justify left bottom) hide)
    )
    (pin "1")
    (pin "2")
    (instances
      (project "kria-k26-devboard"
        (path ""
          (reference "C159") (unit 1)
        )
      )
    )
  )

  (symbol (lib_id "kria-k26-devboard:R_10k_0402") (at 302.26 106.68 270) (unit 1)
    (in_bom yes) (on_board yes) (dnp no) (fields_autoplaced)
    (property "Reference" "R169" (at 299.72 107.95 90)
      (effects (font (size 1.524 1.524)) (justify right))
    )
    (property "Value" "R_10k_0402" (at 298.45 106.68 0)
      (effects (font (size 1.27 1.27) (thickness 0.15)) (justify left bottom) hide)
    )
    (property "Footprint" "kria-k26-devboard-footprints:R_0402_1005Metric" (at 307.34 111.76 0)
      (effects (font (size 1.27 1.27) (thickness 0.15)) (justify left bottom) hide)
    )
    (property "Datasheet" "https://www.bourns.com/docs/product-datasheets/cr.pdf" (at 302.26 106.68 0)
      (effects (font (size 1.27 1.27) (thickness 0.15)) (justify left bottom) hide)
    )
    (property "Manufacturer" "Bourns" (at 312.42 111.76 0)
      (effects (font (size 1.27 1.27) (thickness 0.15)) (justify left bottom) hide)
    )
    (property "MPN" "CR0402-FX-1002GLF" (at 309.88 111.76 0)
      (effects (font (size 1.27 1.27) (thickness 0.15)) (justify left bottom) hide)
    )
    (property "Val" "10k" (at 299.72 111.1249 90)
      (effects (font (size 1.27 1.27) (thickness 0.15)) (justify right))
    )
    (property "License" "Apache-2.0" (at 276.86 127 0)
      (effects (font (size 1.27 1.27) (thickness 0.15)) (justify left bottom) hide)
    )
    (property "Author" "Antmicro" (at 274.32 127 0)
      (effects (font (size 1.27 1.27) (thickness 0.15)) (justify left bottom) hide)
    )
    (property "Tolerance" "1%" (at 292.1 127 0)
      (effects (font (size 1.27 1.27)) (justify left bottom) hide)
    )
    (pin "1")
    (pin "2")
    (instances
      (project "kria-k26-devboard"
        (path ""
          (reference "R169") (unit 1)
        )
      )
    )
  )

  (symbol (lib_id "kria-k26-devboard:GND") (at 110.49 161.29 0) (unit 1)
    (in_bom yes) (on_board yes) (dnp no) (fields_autoplaced)
    (property "Reference" "#PWR0169" (at 110.49 167.64 0)
      (effects (font (size 1.27 1.27)) hide)
    )
    (property "Value" "GND" (at 110.49 165.735 0)
      (effects (font (size 1.27 1.27)))
    )
    (property "Footprint" "" (at 119.38 168.91 0)
      (effects (font (size 1.27 1.27) (thickness 0.15)) (justify left bottom) hide)
    )
    (property "Datasheet" "" (at 119.38 173.99 0)
      (effects (font (size 1.27 1.27) (thickness 0.15)) (justify left bottom) hide)
    )
    (property "Author" "Antmicro" (at 119.38 168.91 0)
      (effects (font (size 1.27 1.27) (thickness 0.15)) (justify left bottom) hide)
    )
    (property "License" "Apache-2.0" (at 119.38 171.45 0)
      (effects (font (size 1.27 1.27) (thickness 0.15)) (justify left bottom) hide)
    )
    (pin "1")
    (instances
      (project "kria-k26-devboard"
        (path ""
          (reference "#PWR0169") (unit 1)
        )
      )
    )
  )

  (symbol (lib_id "kria-k26-devboard:GND") (at 246.38 164.465 0) (unit 1)
    (in_bom yes) (on_board yes) (dnp no) (fields_autoplaced)
    (property "Reference" "#PWR0328" (at 246.38 170.815 0)
      (effects (font (size 1.27 1.27)) hide)
    )
    (property "Value" "GND" (at 246.38 168.91 0)
      (effects (font (size 1.27 1.27)))
    )
    (property "Footprint" "" (at 255.27 172.085 0)
      (effects (font (size 1.27 1.27) (thickness 0.15)) (justify left bottom) hide)
    )
    (property "Datasheet" "" (at 255.27 177.165 0)
      (effects (font (size 1.27 1.27) (thickness 0.15)) (justify left bottom) hide)
    )
    (property "Author" "Antmicro" (at 255.27 172.085 0)
      (effects (font (size 1.27 1.27) (thickness 0.15)) (justify left bottom) hide)
    )
    (property "License" "Apache-2.0" (at 255.27 174.625 0)
      (effects (font (size 1.27 1.27) (thickness 0.15)) (justify left bottom) hide)
    )
    (pin "1")
    (instances
      (project "kria-k26-devboard"
        (path ""
          (reference "#PWR0328") (unit 1)
        )
      )
    )
  )

  (symbol (lib_id "kria-k26-devboard:GND") (at 123.19 64.135 0) (unit 1)
    (in_bom yes) (on_board yes) (dnp no) (fields_autoplaced)
    (property "Reference" "#PWR0334" (at 123.19 70.485 0)
      (effects (font (size 1.27 1.27)) hide)
    )
    (property "Value" "GND" (at 123.19 69.215 0)
      (effects (font (size 1.27 1.27)))
    )
    (property "Footprint" "" (at 132.08 71.755 0)
      (effects (font (size 1.27 1.27) (thickness 0.15)) (justify left bottom) hide)
    )
    (property "Datasheet" "" (at 132.08 76.835 0)
      (effects (font (size 1.27 1.27) (thickness 0.15)) (justify left bottom) hide)
    )
    (property "Author" "Antmicro" (at 132.08 71.755 0)
      (effects (font (size 1.27 1.27) (thickness 0.15)) (justify left bottom) hide)
    )
    (property "License" "Apache-2.0" (at 132.08 74.295 0)
      (effects (font (size 1.27 1.27) (thickness 0.15)) (justify left bottom) hide)
    )
    (pin "1")
    (instances
      (project "kria-k26-devboard"
        (path ""
          (reference "#PWR0334") (unit 1)
        )
      )
    )
  )

  (symbol (lib_id "kria-k26-devboard:GND") (at 38.1 109.855 0) (unit 1)
    (in_bom yes) (on_board yes) (dnp no) (fields_autoplaced)
    (property "Reference" "#PWR0178" (at 38.1 116.205 0)
      (effects (font (size 1.27 1.27)) hide)
    )
    (property "Value" "GND" (at 38.1 114.935 0)
      (effects (font (size 1.27 1.27)))
    )
    (property "Footprint" "" (at 46.99 117.475 0)
      (effects (font (size 1.27 1.27) (thickness 0.15)) (justify left bottom) hide)
    )
    (property "Datasheet" "" (at 46.99 122.555 0)
      (effects (font (size 1.27 1.27) (thickness 0.15)) (justify left bottom) hide)
    )
    (property "Author" "Antmicro" (at 46.99 117.475 0)
      (effects (font (size 1.27 1.27) (thickness 0.15)) (justify left bottom) hide)
    )
    (property "License" "Apache-2.0" (at 46.99 120.015 0)
      (effects (font (size 1.27 1.27) (thickness 0.15)) (justify left bottom) hide)
    )
    (pin "1")
    (instances
      (project "kria-k26-devboard"
        (path ""
          (reference "#PWR0178") (unit 1)
        )
      )
    )
  )

  (symbol (lib_id "kria-k26-devboard:C_100n_0402") (at 165.735 56.515 270) (unit 1)
    (in_bom yes) (on_board yes) (dnp no) (fields_autoplaced)
    (property "Reference" "C160" (at 168.275 57.7913 90)
      (effects (font (size 1.524 1.524)) (justify left))
    )
    (property "Value" "C_100n_0402" (at 161.925 56.515 0)
      (effects (font (size 1.27 1.27) (thickness 0.15)) (justify left bottom) hide)
    )
    (property "Footprint" "kria-k26-devboard-footprints:C_0402_1005Metric" (at 170.815 61.595 0)
      (effects (font (size 1.27 1.27) (thickness 0.15)) (justify left bottom) hide)
    )
    (property "Datasheet" "https://search.murata.co.jp/Ceramy/image/img/A01X/G101/ENG/GRM155R61H104KE14-01.pdf" (at 165.735 56.515 0)
      (effects (font (size 1.27 1.27) (thickness 0.15)) (justify left bottom) hide)
    )
    (property "Manufacturer" "Murata" (at 175.895 61.595 0)
      (effects (font (size 1.27 1.27) (thickness 0.15)) (justify left bottom) hide)
    )
    (property "MPN" "GRM155R61H104KE14D" (at 173.355 61.595 0)
      (effects (font (size 1.27 1.27) (thickness 0.15)) (justify left bottom) hide)
    )
    (property "Val" "100n" (at 168.275 60.9662 90)
      (effects (font (size 1.27 1.27) (thickness 0.15)) (justify left))
    )
    (property "License" "Apache-2.0" (at 142.875 76.835 0)
      (effects (font (size 1.27 1.27) (thickness 0.15)) (justify left bottom) hide)
    )
    (property "Author" "Antmicro" (at 140.335 76.835 0)
      (effects (font (size 1.27 1.27) (thickness 0.15)) (justify left bottom) hide)
    )
    (property "Voltage" "50V" (at 137.795 76.835 0)
      (effects (font (size 1.27 1.27)) (justify left bottom) hide)
    )
    (property "Dielectric" "X5R" (at 135.255 76.835 0)
      (effects (font (size 1.27 1.27)) (justify left bottom) hide)
    )
    (pin "1")
    (pin "2")
    (instances
      (project "kria-k26-devboard"
        (path ""
          (reference "C160") (unit 1)
        )
      )
    )
  )

  (symbol (lib_id "kria-k26-devboard:GND") (at 93.98 64.135 0) (unit 1)
    (in_bom yes) (on_board yes) (dnp no) (fields_autoplaced)
    (property "Reference" "#PWR0333" (at 93.98 70.485 0)
      (effects (font (size 1.27 1.27)) hide)
    )
    (property "Value" "GND" (at 93.98 68.58 0)
      (effects (font (size 1.27 1.27)))
    )
    (property "Footprint" "" (at 102.87 71.755 0)
      (effects (font (size 1.27 1.27) (thickness 0.15)) (justify left bottom) hide)
    )
    (property "Datasheet" "" (at 102.87 76.835 0)
      (effects (font (size 1.27 1.27) (thickness 0.15)) (justify left bottom) hide)
    )
    (property "Author" "Antmicro" (at 102.87 71.755 0)
      (effects (font (size 1.27 1.27) (thickness 0.15)) (justify left bottom) hide)
    )
    (property "License" "Apache-2.0" (at 102.87 74.295 0)
      (effects (font (size 1.27 1.27) (thickness 0.15)) (justify left bottom) hide)
    )
    (pin "1")
    (instances
      (project "kria-k26-devboard"
        (path ""
          (reference "#PWR0333") (unit 1)
        )
      )
    )
  )

  (symbol (lib_id "kria-k26-devboard:TP_0.75mm_SMD") (at 247.65 161.29 0) (unit 1)
    (in_bom yes) (on_board yes) (dnp no) (fields_autoplaced)
    (property "Reference" "TP64" (at 252.73 161.2899 0)
      (effects (font (size 1.27 1.27)) (justify left))
    )
    (property "Value" "TP_0.75mm_SMD" (at 247.65 163.83 0)
      (effects (font (size 1.27 1.27) (thickness 0.15)) (justify left bottom) hide)
    )
    (property "Footprint" "kria-k26-devboard-footprints:TP_SMD_0.75mm" (at 252.73 156.21 0)
      (effects (font (size 1.27 1.27) (thickness 0.15)) (justify left bottom) hide)
    )
    (property "Datasheet" "" (at 252.73 153.67 0)
      (effects (font (size 1.27 1.27) (thickness 0.15)) (justify left bottom) hide)
    )
    (property "MPN" "" (at 247.65 161.29 0)
      (effects (font (size 1.27 1.27) (thickness 0.15)) (justify left bottom) hide)
    )
    (property "Manufacturer" "" (at 247.65 161.29 0)
      (effects (font (size 1.27 1.27) (thickness 0.15)) (justify left bottom) hide)
    )
    (property "Author" "Antmicro" (at 262.89 176.53 0)
      (effects (font (size 1.27 1.27) (thickness 0.15)) (justify left bottom) hide)
    )
    (property "License" "Apache-2.0" (at 262.89 179.07 0)
      (effects (font (size 1.27 1.27) (thickness 0.15)) (justify left bottom) hide)
    )
    (pin "1")
    (instances
      (project "kria-k26-devboard"
        (path ""
          (reference "TP64") (unit 1)
        )
      )
    )
  )

  (symbol (lib_id "kria-k26-devboard:GND") (at 53.34 129.54 0) (unit 1)
    (in_bom yes) (on_board yes) (dnp no) (fields_autoplaced)
    (property "Reference" "#PWR0171" (at 53.34 135.89 0)
      (effects (font (size 1.27 1.27)) hide)
    )
    (property "Value" "GND" (at 53.34 134.62 0)
      (effects (font (size 1.27 1.27)))
    )
    (property "Footprint" "" (at 62.23 137.16 0)
      (effects (font (size 1.27 1.27) (thickness 0.15)) (justify left bottom) hide)
    )
    (property "Datasheet" "" (at 62.23 142.24 0)
      (effects (font (size 1.27 1.27) (thickness 0.15)) (justify left bottom) hide)
    )
    (property "Author" "Antmicro" (at 62.23 137.16 0)
      (effects (font (size 1.27 1.27) (thickness 0.15)) (justify left bottom) hide)
    )
    (property "License" "Apache-2.0" (at 62.23 139.7 0)
      (effects (font (size 1.27 1.27) (thickness 0.15)) (justify left bottom) hide)
    )
    (pin "1")
    (instances
      (project "kria-k26-devboard"
        (path ""
          (reference "#PWR0171") (unit 1)
        )
      )
    )
  )

  (symbol (lib_id "kria-k26-devboard:GND") (at 116.84 161.29 0) (unit 1)
    (in_bom yes) (on_board yes) (dnp no) (fields_autoplaced)
    (property "Reference" "#PWR0170" (at 116.84 167.64 0)
      (effects (font (size 1.27 1.27)) hide)
    )
    (property "Value" "GND" (at 116.84 165.735 0)
      (effects (font (size 1.27 1.27)))
    )
    (property "Footprint" "" (at 125.73 168.91 0)
      (effects (font (size 1.27 1.27) (thickness 0.15)) (justify left bottom) hide)
    )
    (property "Datasheet" "" (at 125.73 173.99 0)
      (effects (font (size 1.27 1.27) (thickness 0.15)) (justify left bottom) hide)
    )
    (property "Author" "Antmicro" (at 125.73 168.91 0)
      (effects (font (size 1.27 1.27) (thickness 0.15)) (justify left bottom) hide)
    )
    (property "License" "Apache-2.0" (at 125.73 171.45 0)
      (effects (font (size 1.27 1.27) (thickness 0.15)) (justify left bottom) hide)
    )
    (pin "1")
    (instances
      (project "kria-k26-devboard"
        (path ""
          (reference "#PWR0170") (unit 1)
        )
      )
    )
  )

  (symbol (lib_id "kria-k26-devboard:C_1u_25V_0603") (at 97.79 36.83 270) (unit 1)
    (in_bom yes) (on_board yes) (dnp no) (fields_autoplaced)
    (property "Reference" "C158" (at 94.615 38.1063 90)
      (effects (font (size 1.524 1.524)) (justify right))
    )
    (property "Value" "C_1u_25V_0603" (at 93.98 36.83 0)
      (effects (font (size 1.27 1.27) (thickness 0.15)) (justify left bottom) hide)
    )
    (property "Footprint" "kria-k26-devboard-footprints:C_0603_1608Metric" (at 102.87 41.91 0)
      (effects (font (size 1.27 1.27) (thickness 0.15)) (justify left bottom) hide)
    )
    (property "Datasheet" " " (at 97.79 36.83 0)
      (effects (font (size 1.27 1.27) (thickness 0.15)) (justify left bottom) hide)
    )
    (property "Manufacturer" "Samsung" (at 107.95 41.91 0)
      (effects (font (size 1.27 1.27) (thickness 0.15)) (justify left bottom) hide)
    )
    (property "MPN" "CL10A105KA8NNNC" (at 105.41 41.91 0)
      (effects (font (size 1.27 1.27) (thickness 0.15)) (justify left bottom) hide)
    )
    (property "Val" "1u/25V" (at 94.615 41.2812 90)
      (effects (font (size 1.27 1.27) (thickness 0.15)) (justify right))
    )
    (property "License" "Apache-2.0" (at 74.93 57.15 0)
      (effects (font (size 1.27 1.27) (thickness 0.15)) (justify left bottom) hide)
    )
    (property "Author" "Antmicro" (at 72.39 57.15 0)
      (effects (font (size 1.27 1.27) (thickness 0.15)) (justify left bottom) hide)
    )
    (property "Voltage" "" (at 69.85 57.15 0)
      (effects (font (size 1.27 1.27)) (justify left bottom) hide)
    )
    (property "Dielectric" "" (at 67.31 57.15 0)
      (effects (font (size 1.27 1.27)) (justify left bottom) hide)
    )
    (pin "1")
    (pin "2")
    (instances
      (project "kria-k26-devboard"
        (path ""
          (reference "C158") (unit 1)
        )
      )
    )
  )

  (symbol (lib_id "kria-k26-devboard:GND") (at 302.26 111.76 0) (unit 1)
    (in_bom yes) (on_board yes) (dnp no) (fields_autoplaced)
    (property "Reference" "#PWR0176" (at 302.26 118.11 0)
      (effects (font (size 1.27 1.27)) hide)
    )
    (property "Value" "GND" (at 302.26 116.205 0)
      (effects (font (size 1.27 1.27)))
    )
    (property "Footprint" "" (at 311.15 119.38 0)
      (effects (font (size 1.27 1.27) (thickness 0.15)) (justify left bottom) hide)
    )
    (property "Datasheet" "" (at 311.15 124.46 0)
      (effects (font (size 1.27 1.27) (thickness 0.15)) (justify left bottom) hide)
    )
    (property "Author" "Antmicro" (at 311.15 119.38 0)
      (effects (font (size 1.27 1.27) (thickness 0.15)) (justify left bottom) hide)
    )
    (property "License" "Apache-2.0" (at 311.15 121.92 0)
      (effects (font (size 1.27 1.27) (thickness 0.15)) (justify left bottom) hide)
    )
    (pin "1")
    (instances
      (project "kria-k26-devboard"
        (path ""
          (reference "#PWR0176") (unit 1)
        )
      )
    )
  )

  (symbol (lib_id "kria-k26-devboard:TP_0.75mm_SMD") (at 247.65 163.83 0) (unit 1)
    (in_bom yes) (on_board yes) (dnp no) (fields_autoplaced)
    (property "Reference" "TP65" (at 252.73 163.8299 0)
      (effects (font (size 1.27 1.27)) (justify left))
    )
    (property "Value" "TP_0.75mm_SMD" (at 247.65 166.37 0)
      (effects (font (size 1.27 1.27) (thickness 0.15)) (justify left bottom) hide)
    )
    (property "Footprint" "kria-k26-devboard-footprints:TP_SMD_0.75mm" (at 252.73 158.75 0)
      (effects (font (size 1.27 1.27) (thickness 0.15)) (justify left bottom) hide)
    )
    (property "Datasheet" "" (at 252.73 156.21 0)
      (effects (font (size 1.27 1.27) (thickness 0.15)) (justify left bottom) hide)
    )
    (property "MPN" "" (at 247.65 163.83 0)
      (effects (font (size 1.27 1.27) (thickness 0.15)) (justify left bottom) hide)
    )
    (property "Manufacturer" "" (at 247.65 163.83 0)
      (effects (font (size 1.27 1.27) (thickness 0.15)) (justify left bottom) hide)
    )
    (property "Author" "Antmicro" (at 262.89 179.07 0)
      (effects (font (size 1.27 1.27) (thickness 0.15)) (justify left bottom) hide)
    )
    (property "License" "Apache-2.0" (at 262.89 181.61 0)
      (effects (font (size 1.27 1.27) (thickness 0.15)) (justify left bottom) hide)
    )
    (pin "1")
    (instances
      (project "kria-k26-devboard"
        (path ""
          (reference "TP65") (unit 1)
        )
      )
    )
  )
)
